;LEADER: 12 
;HEADER: 
;CODE  : ASCII 
;FILE  : DAT6MTH3AD0_t6m_cm_d_brd_103112_274-1-10.drl for board DAT6MTH3AD0_t6m_cm_d_brd_103112_274.brd ... layers TOP and BOTTOM
;   Holesize 1. = 10.000000 Tolerance = +3.000000/-3.000000 PLATED MILS Quantity = 6028
;   Holesize 2. = 10.000000 Tolerance = +4.000000/-10.000000 PLATED MILS Quantity = 12
;   Holesize 3. = 22.000000 Tolerance = +3.000000/-3.000000 PLATED MILS Quantity = 8
;   Holesize 4. = 26.000000 Tolerance = +3.000000/-3.000000 PLATED MILS Quantity = 7
;   Holesize 5. = 33.000000 Tolerance = +3.000000/-3.000000 PLATED MILS Quantity = 15
;   Holesize 6. = 36.000000 Tolerance = +3.000000/-3.000000 PLATED MILS Quantity = 8
;   Holesize 7. = 40.000000 Tolerance = +3.000000/-3.000000 PLATED MILS Quantity = 25
;   Holesize 8. = 41.000000 Tolerance = +3.000000/-3.000000 PLATED MILS Quantity = 2
;   Holesize 9. = 44.000000 Tolerance = +3.000000/-3.000000 PLATED MILS Quantity = 1
;   Holesize 10. = 46.000000 Tolerance = +3.000000/-3.000000 PLATED MILS Quantity = 30
;   Holesize 11. = 48.000000 Tolerance = +3.000000/-3.000000 PLATED MILS Quantity = 4
;   Holesize 12. = 56.000000 Tolerance = +3.000000/-3.000000 PLATED MILS Quantity = 2
;   Holesize 13. = 57.000000 Tolerance = +3.000000/-3.000000 PLATED MILS Quantity = 4
;   Holesize 14. = 90.000000 Tolerance = +3.000000/-3.000000 PLATED MILS Quantity = 8
;   Holesize 15. = 213.000000 Tolerance = +2.000000/-2.000000 PLATED MILS Quantity = 1
;   Holesize 16. = 42.000000 Tolerance = +2.000000/-2.000000 NON_PLATED MILS Quantity = 2
;   Holesize 17. = 46.000000 Tolerance = +2.000000/-2.000000 NON_PLATED MILS Quantity = 1
;   Holesize 18. = 47.000000 Tolerance = +2.000000/-2.000000 NON_PLATED MILS Quantity = 4
;   Holesize 19. = 50.000000 Tolerance = +2.000000/-2.000000 NON_PLATED MILS Quantity = 16
;   Holesize 20. = 59.000000 Tolerance = +2.000000/-2.000000 NON_PLATED MILS Quantity = 2
;   Holesize 21. = 65.000000 Tolerance = +2.000000/-2.000000 NON_PLATED MILS Quantity = 1
;   Holesize 22. = 118.000000 Tolerance = +2.000000/-2.000000 NON_PLATED MILS Quantity = 4
;   Holesize 23. = 120.000000 Tolerance = +2.000000/-2.000000 NON_PLATED MILS Quantity = 2
;   Holesize 24. = 142.000000 Tolerance = +2.000000/-2.000000 NON_PLATED MILS Quantity = 2
;   Holesize 25. = 150.000000 Tolerance = +2.000000/-2.000000 NON_PLATED MILS Quantity = 2
;   Holesize 26. = 158.000000 Tolerance = +2.000000/-2.000000 NON_PLATED MILS Quantity = 1
%
G90
X-0267012Y1044916
X-0294532Y1044846
X-0287932Y1044846
X-0281332Y1044846
X0033841Y0009183
X0023987Y0012977
X0028408Y0026414
X0030274Y0037714
X0034008Y0091017
X0032260Y0096899
X0024411Y0016186
X0028104Y0030414
X0030282Y0034564
X0034149Y0044149
X0021530Y0368991
X0016010Y0369168
X0013120Y0375871
X0018340Y0366452
X0013170Y0372673
X0023860Y0366275
X0033420Y0367309
X0013950Y0388616
X0014240Y0394866
X0013390Y0397543
X0018210Y0386530
X0014140Y0391826
X0028250Y0438740
X0028250Y0472076
X0023610Y0568111
X0020650Y0546243
X0019450Y0550297
X0030672Y0551245
X0033231Y0556346
X0028112Y0591718
X0016200Y0566921
X0017876Y0578422
X0018960Y0572061
X0013510Y0591939
X0020350Y0555807
X0014500Y0601957
X0004390Y0533777
X0034240Y0536966
X0034140Y0540345
X0017020Y0592934
X0033140Y0602232
X0028270Y0602194
X0034440Y0597285
X0021881Y0595792
X0014550Y0628297
X0015349Y0614142
X0011980Y0617956
X0030744Y0617898
X0028185Y0612088
X0024168Y0655750
X0009240Y0638699
X0009300Y0631472
X0013807Y0634826
X0015850Y0610980
X0009360Y0653943
X0014170Y0653991
X0014000Y0658369
X0009260Y0658321
X0011680Y0656335
X0029964Y0658951
X0017071Y0658951
X-0039858Y0731383
X-0031858Y0731383
X-0035858Y0731383
X0097390Y0766435
X0119900Y0754021
X0102421Y0785938
X0106650Y0779581
X0097180Y0786472
X0066880Y0761625
X0089810Y0765905
X0125600Y0759000
X0126220Y0720949
X0132334Y0732982
X0104300Y0773100
X0056500Y0789667
X0064790Y0776777
X0060370Y0776861
X0066860Y0782716
X0062730Y0782694
X0067660Y0779452
X0062290Y0779629
X0058840Y0783097
X0059260Y0779815
X0122720Y0785051
X0127290Y0781982
X0130660Y0785601
X0118169Y0783857
X0116370Y0785941
X0130850Y0782456
X0120090Y0780618
X0125960Y0785699
X0070925Y0791695
X0115748Y0716275
X0123518Y0742030
X0120322Y0742187
X0120357Y0738889
X0100223Y0733207
X0082847Y0716068
X0070925Y0788695
X0082736Y0788695
X0082736Y0791695
X0094547Y0791695
X0094547Y0788695
X0114232Y0788695
X0114232Y0791695
X0110295Y0782191
X0098590Y0782494
X0110295Y0785734
X0102421Y0782191
X0106358Y0785790
X0046890Y0633564
X0059530Y0631704
X0047480Y0616848
X0040980Y0656396
X0044640Y0651029
X0042950Y0612487
X0037920Y0651828
X0061205Y0628870
X0056240Y0630081
X0048060Y0621229
X0051051Y0619407
X0052230Y0614907
X0051038Y0643928
X0053751Y0652029
X0061600Y0653611
X0063650Y0646957
X0063610Y0618917
X0063570Y0613914
X0132050Y0671817
X0059390Y0642906
X0048540Y0624953
X0121070Y0670509
X0061205Y0623870
X0050270Y0627793
X0062160Y0644091
X0132190Y0662616
X0130260Y0679836
X0133490Y0695470
X0133607Y0686699
X0132438Y0704733
X0049720Y0668412
X0096200Y0616325
X0097790Y0613797
X0094070Y0613841
X0094070Y0618986
X0098370Y0619252
X0095350Y0644088
X0098410Y0648878
X0098480Y0646217
X0095310Y0647481
X0117790Y0667235
X0134450Y0682978
X0035862Y0617052
X0036930Y0611082
X0050170Y0636895
X0109260Y0644687
X0109640Y0611890
X0129607Y0686735
X0120909Y0674490
X0128240Y0666583
X0109500Y0616724
X0109410Y0621425
X0109260Y0648989
X0098410Y0680541
X0063490Y0630693
X0063300Y0621755
X0073180Y0611184
X0080630Y0689682
X0068630Y0599945
X0049620Y0574212
X0057070Y0580074
X0049680Y0579709
X0057710Y0572918
X0039370Y0600956
X0040908Y0589691
X0044507Y0594082
X0047557Y0588971
X0039540Y0538464
X0050140Y0550572
X0043467Y0555938
X0075380Y0603914
X0057440Y0585607
X0075380Y0608914
X0050870Y0564008
X0053988Y0568748
X0128087Y0513874
X0130844Y0515128
X0130703Y0512549
X0130596Y0510042
X0133138Y0510114
X0109972Y0519508
X0073057Y0515286
X0070696Y0527237
X0067369Y0522993
X0054988Y0518683
X0053769Y0513033
X0082031Y0523928
X0085346Y0512295
X0050630Y0529281
X0049857Y0520516
X0062253Y0522589
X0118124Y0510811
X0124279Y0523691
X0120300Y0572512
X0054117Y0529098
X0081635Y0521104
X0041957Y0543321
X0085140Y0585213
X0081516Y0577905
X0083030Y0582656
X0081980Y0556851
X0082140Y0560758
X0084990Y0563286
X0088200Y0568111
X0039360Y0604593
X0098803Y0531597
X0095660Y0531362
X0092422Y0531081
X0097366Y0542897
X0097268Y0537055
X0038349Y0555730
X0056148Y0530809
X0065478Y0515110
X0043850Y0602797
X0046140Y0541712
X0081635Y0513104
X0081635Y0517104
X0091458Y0511853
X0112575Y0532934
X0114372Y0518898
X0122018Y0516353
X0037990Y0520218
X0067260Y0546688
X0112627Y0536697
X0114005Y0544358
X0113912Y0541144
X0081491Y0533191
X0080318Y0541026
X0081585Y0536382
X0080318Y0544311
X0061003Y0515110
X0061033Y0510705
X0065438Y0510666
X0066262Y0553344
X0063930Y0560181
X0066181Y0562149
X0063670Y0576040
X0065900Y0566403
X0066036Y0574901
X0065989Y0578115
X0069766Y0582525
X0038807Y0543539
X0073130Y0601599
X0072216Y0540493
X0132960Y0550005
X0125340Y0558090
X0130790Y0595613
X0133590Y0588438
X0108026Y0492500
X0124652Y0509398
X0121644Y0509398
X0126260Y0470267
X0126377Y0466738
X0129028Y0425593
X0064480Y0501596
X0072635Y0508991
X0074291Y0486665
X0087721Y0505817
X0061188Y0487117
X0061357Y0477892
X0061357Y0480892
X0061357Y0483392
X0055982Y0494543
X0061188Y0492117
X0061188Y0489617
X0061676Y0500156
X0086695Y0498180
X0083536Y0498308
X0061676Y0502656
X0121968Y0488481
X0119326Y0489706
X0117026Y0488316
X0115516Y0485696
X0109972Y0509321
X0058830Y0497940
X0056330Y0497940
X0125105Y0489431
X0127705Y0489431
X0058000Y0412641
X0081174Y0503587
X0086050Y0446432
X0086050Y0434470
X0086050Y0437470
X0088617Y0451275
X0086050Y0425112
X0086050Y0443432
X0082617Y0451275
X0085617Y0451275
X0070568Y0451029
X0067568Y0451029
X0064568Y0451029
X0079900Y0442193
X0079900Y0445193
X0079900Y0439193
X0080490Y0423690
X0080490Y0426690
X0080490Y0420690
X0086050Y0428718
X0090238Y0418623
X0090031Y0421693
X0049590Y0469432
X0047200Y0467262
X0049830Y0465496
X0047590Y0463876
X0051670Y0462885
X0049185Y0472713
X0044360Y0433729
X0098470Y0418834
X0105670Y0411262
X0133731Y0493910
X0126072Y0480864
X0127060Y0460040
X0113301Y0499574
X0113372Y0496888
X0113337Y0502080
X0110472Y0496888
X0114072Y0480964
X0037990Y0453022
X0085951Y0410263
X0110436Y0499681
X0110400Y0502223
X0098410Y0421908
X0130794Y0493910
X0101650Y0436075
X0101650Y0433296
X0101650Y0425552
X0101650Y0428745
X0047380Y0494638
X0050330Y0503817
X0053330Y0503817
X0053330Y0506417
X0053622Y0509276
X0101650Y0443038
X0101590Y0446203
X0047420Y0433725
X0051350Y0433695
X0045410Y0430444
X0049640Y0430237
X0044360Y0414915
X0047900Y0414660
X0052150Y0414896
X0045530Y0412473
X0049730Y0412473
X0124040Y0459746
X0121080Y0460060
X0118020Y0455079
X0117980Y0451981
X0123226Y0413925
X0125726Y0413925
X0128226Y0413925
X0085955Y0494485
X0083455Y0494485
X0085955Y0491985
X0085955Y0489485
X0083455Y0491985
X0083455Y0489485
X0088563Y0494484
X0088563Y0489484
X0088563Y0491984
X0049625Y0480972
X0049625Y0478472
X0049645Y0489304
X0049645Y0491804
X0053330Y0497940
X0050330Y0497940
X0061183Y0465314
X0064050Y0465689
X0066747Y0466363
X0118720Y0471989
X0121360Y0472028
X0086726Y0501997
X0114207Y0414910
X0114207Y0417910
X0083245Y0397913
X0083084Y0389621
X0126300Y0390369
X0040690Y0359555
X0035750Y0364593
X0038280Y0362184
X0107531Y0394023
X0095951Y0376661
X0110230Y0363235
X0110230Y0360735
X0113504Y0407673
X0113412Y0404826
X0115727Y0405844
X0122120Y0386736
X0125050Y0384546
X0111120Y0401084
X0108235Y0401017
X0103870Y0399604
X0103810Y0405876
X0103750Y0402740
X0117030Y0389978
X0103151Y0373340
X0074058Y0389621
X0073868Y0397913
X0047820Y0398827
X0050840Y0395761
X0051720Y0384808
X0049750Y0387305
X0053340Y0393132
X0095968Y0367814
X0099968Y0367705
X0116960Y0394023
X0110490Y0397362
X0057624Y0366105
X0073917Y0385722
X0074031Y0393857
X0049244Y0360352
X0125229Y0398001
X0127729Y0398001
X0122729Y0398001
X0068830Y0215817
X0063718Y0239030
X0101020Y0223348
X0082600Y0285426
X0082560Y0288099
X0096990Y0223043
X0130324Y0277096
X0130324Y0272096
X0081165Y0257717
X0104270Y0265662
X0075560Y0218513
X0104550Y0262359
X0128960Y0283696
X0123960Y0283696
X0057994Y0287655
X0098700Y0234650
X0086479Y0249259
X0088399Y0244041
X0129650Y0255414
X0129650Y0250414
X0056287Y0242872
X0083390Y0235665
X0086172Y0213852
X0079142Y0237920
X0078207Y0279092
X0078220Y0281745
X0078373Y0276029
X0061945Y0267579
X0079217Y0232861
X0078614Y0229920
X0072150Y0225148
X0078190Y0214642
X0056936Y0223944
X0056383Y0218543
X0081210Y0261337
X0129610Y0287115
X0123160Y0287060
X0130310Y0269174
X0129660Y0279890
X0126460Y0250160
X0126570Y0256194
X0054062Y0257049
X0063720Y0228683
X0072368Y0287906
X0079544Y0267579
X0106517Y0210796
X0093200Y0300734
X0096168Y0231618
X0085876Y0218939
X0082368Y0297135
X0174166Y0007449
X0181735Y0007369
X0171666Y0007449
X0179235Y0007369
X0191735Y0007369
X0189235Y0007369
X0150787Y0009246
X0072190Y0297395
X0077368Y0299206
X0066818Y0297483
X0077239Y0260814
X0068690Y0175589
X0066570Y0189983
X0076880Y0126528
X0150592Y0020974
X0146380Y0020345
X0073870Y0205758
X0140350Y0081347
X0135290Y0087664
X0233290Y0051045
X0229310Y0051103
X0225310Y0051103
X0221310Y0051103
X0230290Y0045504
X0226290Y0045504
X0222290Y0045504
X0147427Y0030367
X0164550Y0061239
X0158165Y0021300
X0168040Y0061462
X0152810Y0029921
X0176090Y0026906
X0180907Y0027544
X0173110Y0026877
X0191596Y0027620
X0188634Y0027860
X0183407Y0027544
X0157010Y0058963
X0165336Y0046126
X0165959Y0027133
X0162350Y0042984
X0160731Y0041038
X0168961Y0027073
X0139932Y0035310
X0157877Y0030674
X0137872Y0029551
X0149025Y0051720
X0159861Y0036134
X0139931Y0040842
X0141490Y0019267
X0143857Y0051943
X0137540Y0058255
X0135050Y0053493
X0180159Y0040661
X0151618Y0083343
X0226620Y0089385
X0204003Y0091247
X0196653Y0091837
X0156440Y0074863
X0064309Y0141882
X0188203Y0104567
X0220200Y0093561
X0174710Y0105699
X0177680Y0101764
X0167383Y0093147
X0199993Y0103637
X0164280Y0101810
X0222983Y0091587
X0219510Y0101338
X0213908Y0096975
X0071510Y0164548
X0205903Y0101477
X0189928Y0091847
X0177733Y0091967
X0190100Y0099701
X0076030Y0156152
X0173900Y0097662
X0068930Y0197193
X0233083Y0094817
X0063900Y0112081
X0220983Y0106174
X0234243Y0100156
X0230643Y0108497
X0055230Y0112521
X0208908Y0096975
X0183013Y0098813
X0215773Y0090147
X0214320Y0101978
X0169510Y0106579
X0231013Y0091547
X0212423Y0104957
X0196493Y0105637
X0168850Y0099251
X0101449Y0194368
X0184928Y0091847
X0200480Y0097687
X0156255Y0045743
X0157659Y0047891
X0102257Y0167955
X0067853Y0180744
X0194861Y0012952
X0194825Y0010196
X0198577Y0015374
X0201849Y0015292
X0204978Y0010605
X0204785Y0013762
X0114920Y0179082
X0106090Y0167615
X0106760Y0175370
X0112530Y0186363
X0108910Y0193194
X0111220Y0160923
X0085010Y0171679
X0090905Y0199733
X0082553Y0185431
X0074470Y0175666
X0059640Y0161376
X0078850Y0157866
X0075359Y0201109
X0075236Y0188946
X0231910Y0105731
X0217040Y0103121
X0171950Y0105105
X0165690Y0098835
X0186060Y0100103
X0214573Y0093771
X0206273Y0098364
X0184170Y0095213
X0177210Y0097657
X0055963Y0199565
X0072890Y0154349
X0225600Y0066317
X0221990Y0021219
X0046811Y0122928
X0057749Y0204326
X0057257Y0180712
X0056190Y0170026
X0082030Y0191733
X0086560Y0205852
X0090878Y0177967
X0098531Y0121340
X0229725Y0088719
X0220276Y0088440
X0213190Y0088414
X0219095Y0108675
X0210203Y0108457
X0202560Y0107797
X0206103Y0088207
X0199016Y0088434
X0191930Y0088507
X0184843Y0088467
X0195473Y0108767
X0168308Y0088412
X0177757Y0088271
X0180990Y0108770
X0161221Y0089447
X0160040Y0108844
X0130350Y0134167
X0130350Y0130400
X0068756Y0167695
X0054703Y0122796
X0169149Y0050968
X0152789Y0053124
X0149157Y0060010
X0145210Y0060154
X0147497Y0042983
X0147461Y0038078
X0152366Y0042983
X0152412Y0038112
X0154592Y0021173
X0137500Y0025494
X0146558Y0074863
X0166639Y0013027
X0164139Y0013027
X0175280Y0012401
X0171310Y0012450
X0153863Y0015176
X0158181Y0011978
X0225990Y0021219
X0229990Y0021219
X0221600Y0066317
X0233600Y0066317
X0229600Y0066317
X0172224Y0051601
X0174724Y0054101
X0177224Y0054101
X0172224Y0054101
X0172224Y0049101
X0174724Y0051601
X0177224Y0051601
X0174724Y0049101
X0177224Y0049101
X0196000Y0095568
X0081030Y0172605
X0129780Y0092580
X0128330Y0098360
X0047510Y0109421
X0124150Y0094643
X0129580Y0086837
X0132400Y0088153
X0125480Y0091163
X0130195Y0019162
X0230890Y0169424
X0230650Y0164566
X0230749Y0160807
X0230100Y0187389
X0231000Y0173381
X0230140Y0197240
X0049559Y0050577
X0126220Y0083291
X0126220Y0080364
X0210623Y0121267
X0173170Y0123367
X0168170Y0123367
X0159190Y0127781
X0054800Y0025547
X0042205Y0021518
X0051580Y0017595
X0056610Y0020553
X0054981Y0059420
X0046570Y0073891
X0051340Y0069181
X0228138Y0125802
X0064190Y0072841
X0054101Y0074252
X0177763Y0121057
X0061760Y0107321
X0164490Y0127110
X0194463Y0122631
X0044010Y0055170
X0131068Y0076588
X0036848Y0025198
X0036588Y0032278
X0049890Y0030392
X0233138Y0125802
X0046981Y0058690
X0050981Y0058681
X0060318Y0065593
X0041685Y0073110
X0039126Y0084631
X0036567Y0107988
X0162130Y0129344
X0174213Y0120569
X0167127Y0120603
X0054860Y0016952
X0045410Y0021563
X0233268Y0121742
X0226713Y0122007
X0207041Y0184502
X0207154Y0175212
X0207070Y0179744
X0207070Y0188978
X0186730Y0121202
X0135590Y0130449
X0135640Y0134167
X0112386Y0071874
X0115628Y0104405
X0082065Y0073224
X0080845Y0106859
X0059524Y0025922
X0043480Y0034592
X0079360Y0046044
X0131474Y0043439
X0045578Y0050478
X0062981Y0059440
X0066981Y0059390
X0057040Y0073421
X0129860Y0014571
X0097830Y0066508
X0196010Y0125188
X0036567Y0073145
X0178941Y0270160
X0206299Y0293698
X0183198Y0278034
X0191860Y0270148
X0175110Y0260412
X0158076Y0290635
X0201518Y0265990
X0178929Y0262244
X0134540Y0267786
X0152733Y0288517
X0231749Y0259139
X0194205Y0271034
X0231710Y0240242
X0231710Y0243642
X0233793Y0260697
X0201518Y0268887
X0225973Y0259197
X0231749Y0262139
X0233793Y0263697
X0233904Y0252772
X0233793Y0257697
X0233793Y0266697
X0227517Y0244187
X0225973Y0265197
X0203149Y0290548
X0202525Y0299358
X0149721Y0292987
X0206319Y0296863
X0192298Y0286183
X0213138Y0274187
X0139950Y0293835
X0215749Y0281098
X0203149Y0281098
X0215749Y0287398
X0215749Y0293698
X0218899Y0303148
X0231648Y0274243
X0228821Y0274197
X0148350Y0281769
X0218899Y0299998
X0137990Y0296735
X0152634Y0276809
X0138930Y0278965
X0145200Y0276468
X0154546Y0256986
X0148330Y0258806
X0167698Y0260617
X0167322Y0255855
X0210303Y0271227
X0198296Y0232699
X0178818Y0274540
X0181818Y0274540
X0170829Y0271452
X0174078Y0271435
X0194693Y0262197
X0194693Y0259197
X0232948Y0234047
X0216109Y0271139
X0186873Y0260697
X0198685Y0244085
X0200469Y0259139
X0202402Y0263713
X0198685Y0237385
X0185798Y0256760
X0205271Y0240209
X0218508Y0256664
X0216109Y0262139
X0188899Y0236808
X0184296Y0241098
X0178040Y0228978
X0200977Y0256305
X0211935Y0230585
X0217135Y0237385
X0144400Y0247561
X0144400Y0244061
X0205566Y0243497
X0211935Y0240785
X0217135Y0230585
X0205535Y0228682
X0183550Y0235060
X0216109Y0265139
X0184050Y0230139
X0176301Y0262624
X0201994Y0261248
X0210305Y0262289
X0173263Y0262589
X0157690Y0249918
X0177891Y0249324
X0206299Y0281098
X0210303Y0268227
X0216184Y0268587
X0186873Y0263697
X0205535Y0234497
X0217135Y0240785
X0225973Y0262197
X0181602Y0262656
X0226010Y0240342
X0184117Y0264852
X0216512Y0258490
X0211935Y0237385
X0195126Y0249955
X0174148Y0289289
X0188658Y0256870
X0226010Y0233542
X0152990Y0248096
X0188899Y0240208
X0210305Y0259330
X0178810Y0287263
X0206299Y0290548
X0206299Y0303148
X0232118Y0271587
X0224357Y0273228
X0181176Y0257643
X0175756Y0257668
X0154581Y0308767
X0206299Y0306298
X0149020Y0303498
X0183440Y0269816
X0187907Y0308784
X0188810Y0301998
X0183254Y0295023
X0196867Y0294342
X0209449Y0281098
X0212610Y0306305
X0231499Y0293698
X0231499Y0296848
X0231499Y0284248
X0231499Y0299998
X0222049Y0299998
X0218899Y0306298
X0222049Y0306298
X0225199Y0306298
X0215749Y0290548
X0212599Y0287398
X0222049Y0287398
X0225199Y0284248
X0225199Y0290548
X0206299Y0287398
X0203149Y0287398
X0209449Y0290548
X0209449Y0287398
X0196812Y0308619
X0188418Y0278887
X0191054Y0294424
X0191949Y0301987
X0181921Y0301920
X0178921Y0301920
X0175921Y0301920
X0231450Y0290583
X0225160Y0293676
X0218899Y0281098
X0167483Y0239914
X0178025Y0279018
X0180510Y0233307
X0147160Y0242219
X0137091Y0301799
X0136130Y0305640
X0137925Y0290987
X0143150Y0281123
X0141682Y0269829
X0162181Y0303075
X0161767Y0287242
X0161918Y0293869
X0158583Y0285548
X0162484Y0276599
X0160449Y0259605
X0162317Y0249877
X0175659Y0286984
X0175162Y0293934
X0170510Y0275522
X0175318Y0278687
X0170617Y0267326
X0171668Y0256287
X0167467Y0243242
X0171320Y0243601
X0184318Y0247612
X0189192Y0243061
X0193677Y0243855
X0188821Y0232784
X0184754Y0302843
X0186254Y0295023
X0184812Y0292979
X0187812Y0286352
X0193557Y0294428
X0186118Y0270787
X0184829Y0259139
X0188442Y0252643
X0193735Y0265857
X0194056Y0256697
X0199509Y0278094
X0201667Y0274542
X0222049Y0303148
X0222049Y0290548
X0212599Y0281098
X0217135Y0244085
X0218899Y0309448
X0231499Y0309448
X0231749Y0265139
X0233793Y0269697
X0231499Y0287398
X0223929Y0263639
X0218153Y0263697
X0218153Y0260697
X0224794Y0256754
X0215761Y0252833
X0219772Y0252659
X0216109Y0274139
X0225199Y0281098
X0212599Y0293698
X0225199Y0287398
X0212599Y0290548
X0212599Y0303148
X0212599Y0299998
X0222049Y0309448
X0225199Y0303148
X0225199Y0299998
X0225199Y0309448
X0212020Y0234359
X0198685Y0240785
X0211935Y0244085
X0208289Y0263639
X0206144Y0252477
X0208129Y0257519
X0210333Y0265197
X0211028Y0255696
X0208226Y0269697
X0185991Y0279041
X0190918Y0277687
X0183698Y0285693
X0193812Y0308619
X0194771Y0302176
X0174138Y0243873
X0175118Y0274287
X0180254Y0295023
X0177470Y0294933
X0163518Y0243987
X0161918Y0254287
X0147570Y0249033
X0172760Y0406540
X0175663Y0386424
X0160710Y0384044
X0150918Y0318134
X0232647Y0396011
X0231223Y0391424
X0190557Y0325701
X0203166Y0312577
X0162071Y0336947
X0156448Y0336629
X0145284Y0401507
X0145295Y0404388
X0135181Y0402121
X0135088Y0405060
X0141847Y0401820
X0141800Y0404481
X0137889Y0403348
X0232804Y0336181
X0232769Y0333207
X0200590Y0327615
X0218947Y0312617
X0231257Y0362218
X0233635Y0357082
X0228419Y0356855
X0208700Y0328000
X0224711Y0325922
X0224585Y0322992
X0225199Y0315748
X0224949Y0328707
X0228729Y0385227
X0216633Y0384989
X0205790Y0387003
X0206380Y0402201
X0210880Y0402359
X0213710Y0402237
X0185074Y0380726
X0191159Y0317171
X0193957Y0317064
X0160886Y0380294
X0183228Y0317023
X0223085Y0401702
X0196273Y0403152
X0196476Y0317042
X0193590Y0383383
X0186350Y0317116
X0201267Y0403294
X0208000Y0325200
X0214406Y0395539
X0200572Y0323920
X0180440Y0398056
X0183254Y0310663
X0200211Y0321446
X0180430Y0392969
X0192681Y0377554
X0186254Y0310663
X0218090Y0390891
X0195420Y0372406
X0215120Y0399654
X0209449Y0312598
X0214786Y0388603
X0192040Y0333606
X0192230Y0337322
X0150510Y0336306
X0230725Y0325649
X0151230Y0330164
X0233136Y0367070
X0175155Y0380727
X0150902Y0379714
X0221280Y0340579
X0231144Y0338225
X0227745Y0368007
X0223095Y0336241
X0230010Y0373300
X0206973Y0361900
X0162940Y0406188
X0222225Y0364031
X0230725Y0334547
X0224996Y0334617
X0214007Y0362701
X0222911Y0333155
X0214657Y0356205
X0203058Y0315593
X0206299Y0315748
X0222974Y0356134
X0223166Y0338842
X0145580Y0316836
X0176371Y0404721
X0184927Y0383876
X0171934Y0386364
X0178660Y0388418
X0151820Y0385554
X0197938Y0376839
X0224108Y0388029
X0232782Y0327096
X0231567Y0321742
X0165290Y0385948
X0145720Y0311336
X0146100Y0323543
X0231499Y0312598
X0225199Y0312598
X0198880Y0310245
X0174500Y0383383
X0175290Y0389582
X0161640Y0403286
X0144058Y0376025
X0136506Y0332193
X0135224Y0323543
X0134768Y0319043
X0135730Y0314543
X0161513Y0317143
X0159564Y0328013
X0161687Y0310355
X0150524Y0382808
X0160058Y0375818
X0152058Y0376016
X0180254Y0310663
X0176037Y0309845
X0167951Y0380551
X0168058Y0376035
X0176058Y0376568
X0177672Y0358103
X0177029Y0347811
X0177720Y0352522
X0177604Y0355155
X0174876Y0336549
X0177359Y0332553
X0167383Y0341306
X0175330Y0318552
X0180342Y0316469
X0178812Y0324259
X0192676Y0402961
X0184058Y0376479
X0186908Y0352760
X0192519Y0352761
X0186925Y0355812
X0184367Y0337792
X0185195Y0332852
X0186296Y0326366
X0193313Y0325492
X0195254Y0310663
X0206657Y0356116
X0198987Y0353137
X0207274Y0353124
X0197243Y0344518
X0201489Y0339107
X0201489Y0336207
X0200905Y0333776
X0208485Y0332356
X0207310Y0330149
X0209300Y0322800
X0203880Y0385272
X0200439Y0390168
X0202823Y0376922
X0206817Y0358874
X0221438Y0390655
X0214008Y0385165
X0223561Y0385108
X0214888Y0352909
X0222777Y0353066
X0228057Y0352837
X0223010Y0344242
X0217129Y0333207
X0217067Y0339542
X0217129Y0336207
X0232172Y0388814
X0230725Y0331649
X0233055Y0339936
X0233697Y0353961
X0217129Y0324207
X0212600Y0319100
X0215085Y0325649
X0217129Y0327207
X0222049Y0312598
X0200488Y0396425
X0206299Y0312598
X0192293Y0340792
X0187404Y0343998
X0194231Y0390267
X0194330Y0396425
X0166189Y0335285
X0168110Y0350642
X0159285Y0336220
X0164418Y0348187
X0162017Y0324389
X0162063Y0327940
X0215100Y0322700
X0187417Y0508756
X0163377Y0484538
X0158406Y0500016
X0152554Y0494027
X0225024Y0442467
X0221858Y0442300
X0218483Y0442550
X0227816Y0442675
X0221406Y0436560
X0224730Y0418003
X0231885Y0442252
X0228906Y0436560
X0228906Y0427560
X0228906Y0433560
X0231870Y0439511
X0228713Y0419525
X0228713Y0416525
X0228906Y0424560
X0136470Y0481994
X0139310Y0478102
X0228604Y0479682
X0226255Y0472579
X0223786Y0476638
X0165707Y0506156
X0169728Y0487664
X0138437Y0438430
X0138437Y0435930
X0138437Y0440930
X0150547Y0459363
X0135300Y0468444
X0146240Y0472111
X0154370Y0449930
X0147576Y0450279
X0147576Y0447779
X0147576Y0445279
X0200459Y0487253
X0230476Y0508891
X0139395Y0425090
X0171616Y0467804
X0142239Y0422346
X0231461Y0462591
X0234209Y0480953
X0189077Y0438281
X0170361Y0428595
X0182132Y0418327
X0173381Y0424005
X0192527Y0429049
X0179562Y0424001
X0170683Y0436834
X0167527Y0420268
X0224209Y0491853
X0223709Y0505353
X0230476Y0502591
X0197161Y0465628
X0204584Y0462478
X0218040Y0473853
X0222419Y0479933
X0227284Y0502591
X0151145Y0469456
X0176220Y0448247
X0178961Y0448138
X0222209Y0489353
X0219309Y0489353
X0215409Y0479253
X0212809Y0479053
X0223953Y0463550
X0228242Y0463681
X0233626Y0508891
X0233309Y0472553
X0168370Y0477790
X0193500Y0489796
X0233626Y0502591
X0180125Y0451946
X0177525Y0451946
X0181923Y0442544
X0181923Y0445044
X0184523Y0441915
X0147820Y0441929
X0135507Y0421367
X0154307Y0507507
X0161563Y0432521
X0161577Y0436834
X0179857Y0477790
X0173151Y0427552
X0175993Y0414924
X0170506Y0424127
X0184920Y0508626
X0190700Y0418325
X0200434Y0478345
X0197809Y0469953
X0200039Y0451350
X0227329Y0508894
X0227326Y0505741
X0224209Y0494928
X0213209Y0488853
X0213994Y0466054
X0226276Y0460704
X0230476Y0505741
X0216209Y0488853
X0200039Y0448750
X0182879Y0435312
X0182877Y0430662
X0192069Y0444852
X0185747Y0487664
X0178217Y0435317
X0178232Y0430642
X0185271Y0421513
X0182771Y0421513
X0185271Y0424013
X0182771Y0424013
X0170444Y0448387
X0172944Y0448387
X0211379Y0501904
X0208710Y0500856
X0189007Y0514846
X0187875Y0534128
X0190434Y0546870
X0188927Y0537836
X0184384Y0543955
X0181491Y0557436
X0182480Y0566819
X0178117Y0528187
X0173217Y0536556
X0153967Y0517186
X0154038Y0511386
X0159186Y0534504
X0162335Y0528206
X0154900Y0548682
X0159185Y0547103
X0154945Y0539233
X0154410Y0557990
X0157611Y0557468
X0159186Y0553402
X0230476Y0521489
X0169615Y0519216
X0233626Y0537236
X0169157Y0548676
X0171606Y0527511
X0172087Y0510536
X0233626Y0512040
X0172889Y0562710
X0230476Y0512040
X0215946Y0544202
X0181232Y0553402
X0167027Y0536376
X0204309Y0539953
X0230476Y0527788
X0191457Y0531553
X0178083Y0553402
X0202486Y0551130
X0162336Y0550253
X0233626Y0540386
X0230476Y0518339
X0173252Y0515693
X0167027Y0539526
X0207309Y0539953
X0230476Y0540386
X0167105Y0552882
X0214118Y0528583
X0174395Y0527975
X0219960Y0601373
X0219960Y0596373
X0136420Y0599352
X0227100Y0580916
X0207178Y0591595
X0210790Y0566926
X0218950Y0565589
X0198890Y0584105
X0233626Y0534087
X0159185Y0537654
X0174720Y0531356
X0211287Y0528547
X0172371Y0519783
X0223376Y0523322
X0199539Y0537112
X0181232Y0537654
X0230476Y0524639
X0166837Y0523486
X0233626Y0518339
X0178085Y0512456
X0178085Y0518755
X0154246Y0527468
X0155400Y0533436
X0149477Y0532733
X0146920Y0547677
X0144120Y0547577
X0219328Y0528823
X0168617Y0525756
X0169444Y0558757
X0230476Y0543536
X0230476Y0537236
X0162335Y0543954
X0218751Y0543835
X0173163Y0551903
X0174930Y0547106
X0186841Y0545372
X0233626Y0524639
X0169491Y0529702
X0166297Y0532416
X0159180Y0528227
X0181232Y0515607
X0211609Y0516553
X0188640Y0530667
X0159196Y0515612
X0230476Y0515190
X0168243Y0542706
X0230476Y0534087
X0154475Y0530422
X0217609Y0516353
X0181231Y0512455
X0193466Y0546886
X0233626Y0515190
X0162335Y0512456
X0205257Y0528822
X0162335Y0521906
X0154126Y0524411
X0178094Y0531365
X0233626Y0527788
X0143252Y0573105
X0162786Y0568599
X0179740Y0568951
X0175386Y0569589
X0166786Y0569056
X0209590Y0580893
X0160699Y0587904
X0178416Y0587849
X0234370Y0593242
X0212342Y0536729
X0174105Y0542290
X0204024Y0609135
X0197709Y0567464
X0204024Y0604135
X0164259Y0557273
X0233626Y0543536
X0178099Y0550267
X0205286Y0551130
X0159179Y0521893
X0184843Y0533995
X0168189Y0514331
X0233626Y0521489
X0197230Y0595335
X0181330Y0587535
X0166605Y0587860
X0153422Y0603043
X0153330Y0599935
X0153527Y0597138
X0197030Y0598535
X0196907Y0605012
X0166930Y0578435
X0166570Y0583874
X0161280Y0581585
X0175330Y0578535
X0177830Y0583535
X0172430Y0584035
X0156480Y0583315
X0191500Y0571956
X0193080Y0581235
X0197730Y0572893
X0201510Y0576885
X0210040Y0576893
X0229269Y0597682
X0211240Y0572893
X0209940Y0584893
X0225100Y0597453
X0144710Y0598135
X0145880Y0584125
X0141190Y0597685
X0139402Y0513707
X0158430Y0568437
X0154900Y0551832
X0155109Y0561153
X0162315Y0553391
X0154945Y0536083
X0154945Y0542383
X0155060Y0545526
X0159185Y0543953
X0153731Y0520734
X0159185Y0531356
X0154517Y0513931
X0171053Y0569411
X0169293Y0562358
X0178082Y0537654
X0186467Y0514036
X0186417Y0518526
X0184386Y0553406
X0188383Y0556895
X0184384Y0537656
X0181232Y0543953
X0181232Y0528205
X0207010Y0602472
X0207476Y0608936
X0208109Y0551053
X0199709Y0551653
X0201509Y0539853
X0209886Y0539962
X0208050Y0528883
X0219296Y0604811
X0218859Y0593093
X0220428Y0580271
X0223561Y0561475
X0216564Y0528902
X0214626Y0516492
X0229809Y0583627
X0231209Y0566282
X0221591Y0563371
X0216590Y0570850
X0223453Y0578087
X0188654Y0573395
X0184932Y0600537
X0185032Y0606737
X0165832Y0606037
X0165832Y0600337
X0173432Y0600437
X0179532Y0600437
X0151900Y0590454
X0139365Y0516636
X0145020Y0576001
X0196740Y0589735
X0141260Y0588175
X0149050Y0588044
X0145550Y0588088
X0154140Y0577815
X0150380Y0602885
X0212635Y0665604
X0167810Y0668131
X0164812Y0662579
X0233584Y0652519
X0138726Y0696707
X0135280Y0679212
X0171180Y0683815
X0190375Y0695624
X0233954Y0697395
X0197243Y0697899
X0211236Y0695586
X0162530Y0636435
X0162530Y0643235
X0140110Y0675907
X0208904Y0611515
X0208904Y0616515
X0139158Y0686725
X0197130Y0626135
X0215604Y0621977
X0225179Y0642614
X0218308Y0635939
X0191910Y0650055
X0187410Y0659705
X0187410Y0649715
X0196410Y0650155
X0205410Y0650035
X0200910Y0650155
X0197889Y0671226
X0202518Y0673273
X0225237Y0671772
X0201411Y0708231
X0178982Y0688631
X0148200Y0669205
X0191542Y0691925
X0199350Y0692724
X0181950Y0698191
X0181744Y0694829
X0200692Y0704081
X0197582Y0703474
X0221340Y0697995
X0185993Y0682670
X0199590Y0682868
X0218240Y0674433
X0223741Y0700554
X0220580Y0692876
X0223707Y0695436
X0211560Y0670575
X0224336Y0687758
X0224060Y0690317
X0167315Y0684943
X0165628Y0691289
X0168645Y0688064
X0169619Y0693335
X0169268Y0697399
X0169396Y0701006
X0169268Y0705304
X0165012Y0675887
X0160112Y0674990
X0155957Y0674813
X0151915Y0675068
X0150840Y0682436
X0164092Y0688014
X0163018Y0684381
X0160101Y0687962
X0152222Y0678394
X0165167Y0681311
X0157287Y0678138
X0159590Y0683050
X0161994Y0678445
X0155650Y0681515
X0151567Y0687579
X0148487Y0676041
X0148140Y0660112
X0205221Y0630886
X0197230Y0615435
X0182353Y0631612
X0174479Y0631986
X0191480Y0639135
X0162668Y0631897
X0153955Y0620760
X0153712Y0610917
X0167530Y0631935
X0200910Y0659735
X0228290Y0629893
X0172510Y0639771
X0169930Y0635329
X0229199Y0642180
X0157963Y0633735
X0210824Y0692266
X0205410Y0661200
X0199510Y0663158
X0179120Y0639615
X0182480Y0634585
X0184748Y0639687
X0202510Y0624005
X0202450Y0663633
X0171270Y0655650
X0143823Y0682907
X0147753Y0627557
X0157963Y0643289
X0178278Y0697976
X0178278Y0701976
X0178278Y0705976
X0174761Y0663816
X0179180Y0675205
X0187744Y0708356
X0187798Y0704513
X0194508Y0704476
X0182163Y0684555
X0188200Y0672526
X0185032Y0612937
X0209238Y0674373
X0213365Y0692151
X0224360Y0684366
X0224289Y0680081
X0215768Y0671993
X0221129Y0642363
X0215948Y0629977
X0216107Y0637977
X0215985Y0633977
X0215699Y0625977
X0229584Y0652668
X0229895Y0671672
X0211760Y0610915
X0211862Y0617709
X0184932Y0619437
X0196463Y0685036
X0171180Y0652009
X0166388Y0647435
X0177038Y0647135
X0165832Y0613137
X0165832Y0619437
X0178632Y0619437
X0172532Y0619537
X0147750Y0687539
X0145750Y0630254
X0199786Y0618893
X0203065Y0638700
X0192130Y0632235
X0197480Y0639815
X0200380Y0629085
X0145570Y0780580
X0146150Y0783820
X0177920Y0739302
X0149450Y0780429
X0149810Y0783858
X0167350Y0778074
X0169860Y0782086
X0172600Y0780150
X0169350Y0785470
X0160320Y0786346
X0153320Y0783499
X0164630Y0781222
X0155170Y0780656
X0160480Y0777583
X0163138Y0778565
X0175463Y0720245
X0230440Y0724242
X0224410Y0719970
X0225940Y0736437
X0225940Y0733671
X0227650Y0720791
X0216820Y0723301
X0138198Y0712628
X0169531Y0710542
X0171154Y0715673
X0211897Y0723870
X0186164Y0724134
X0191150Y0724108
X0205440Y0712510
X0196079Y0723943
X0222710Y0713706
X0200817Y0724180
X0205883Y0724373
X0212350Y0773283
X0206210Y0771577
X0189770Y0778082
X0182500Y0780786
X0177224Y0777765
X0174954Y0728404
X0234011Y0772902
X0226670Y0773299
X0220960Y0778561
X0218270Y0785657
X0199760Y0763929
X0192949Y0771020
X0202050Y0784919
X0180820Y0717914
X0165599Y0730476
X0167568Y0743335
X0158881Y0730784
X0161981Y0730784
X0144631Y0735955
X0145040Y0740741
X0155230Y0740259
X0154400Y0744337
X0147290Y0744113
X0158970Y0743927
X0162640Y0743927
X0154970Y0736966
X0203611Y0722303
X0209017Y0722344
X0193566Y0722333
X0198566Y0722353
X0183566Y0722353
X0188566Y0722353
X0213310Y0719064
X0139680Y0784596
X0135610Y0784521
X0221320Y0720698
X0217530Y0715305
X0135470Y0781697
X0139600Y0781281
X0137070Y0728012
X0134720Y0742382
X0134753Y0726161
X0134777Y0734726
X0134777Y0738726
X0171689Y0728920
X0178278Y0709976
X0182674Y0730521
X0185440Y0735681
X0189940Y0735681
X0194440Y0735623
X0191930Y0712624
X0196144Y0712602
X0185440Y0712499
X0203440Y0735681
X0207940Y0735681
X0198940Y0712499
X0201663Y0712694
X0210023Y0712842
X0198940Y0735681
X0225940Y0724061
X0221440Y0735934
X0216940Y0736063
X0226610Y0713482
X0230440Y0736412
X0212440Y0735829
X0149860Y0726626
X0141791Y0791695
X0141791Y0788695
X0173287Y0788695
X0173287Y0791695
X0200846Y0791695
X0200846Y0788695
X0212658Y0788695
X0212658Y0791695
X0220532Y0791695
X0220532Y0788695
X0232343Y0788695
X0232343Y0791695
X0318090Y0712846
X0312972Y0712693
X0295700Y0733133
X0234940Y0736392
X0252940Y0733567
X0239500Y0733523
X0243940Y0736412
X0250630Y0719457
X0234940Y0733355
X0234910Y0720816
X0248530Y0721829
X0239210Y0720040
X0291318Y0713875
X0297223Y0715523
X0296885Y0718059
X0309531Y0714298
X0255310Y0715915
X0284020Y0724956
X0258570Y0722981
X0270940Y0722080
X0325560Y0713391
X0293300Y0718944
X0289150Y0718548
X0314930Y0724533
X0330410Y0712895
X0319620Y0716403
X0248770Y0724631
X0264600Y0723086
X0321930Y0724895
X0293480Y0725080
X0285880Y0722268
X0288390Y0734796
X0307280Y0733705
X0298590Y0733669
X0275880Y0722141
X0280210Y0734805
X0271210Y0718000
X0285130Y0714433
X0281830Y0722184
X0289060Y0722193
X0305213Y0720393
X0311990Y0717601
X0321820Y0712680
X0260680Y0712988
X0234960Y0714064
X0242680Y0712337
X0293440Y0748380
X0284532Y0747493
X0307146Y0769416
X0302810Y0733807
X0304740Y0777277
X0299249Y0771403
X0295100Y0786269
X0291340Y0771217
X0286722Y0785929
X0281930Y0773190
X0275627Y0777692
X0252470Y0785797
X0247900Y0778823
X0242230Y0774803
X0236180Y0786517
X0272175Y0783074
X0326280Y0775980
X0320440Y0771967
X0320657Y0779595
X0315020Y0780559
X0264340Y0778780
X0263430Y0770417
X0256650Y0778342
X0329590Y0724283
X0303681Y0714421
X0307113Y0713003
X0298160Y0736489
X0279587Y0791695
X0259902Y0791695
X0252028Y0791695
X0234940Y0724325
X0239440Y0736140
X0238348Y0712469
X0252940Y0736318
X0257440Y0736041
X0248440Y0736163
X0253340Y0724726
X0254940Y0712381
X0270940Y0735642
X0266440Y0736030
X0261940Y0735878
X0283990Y0734977
X0289240Y0724687
X0279940Y0724126
X0278341Y0717269
X0302660Y0736359
X0297940Y0724377
X0306540Y0724266
X0291790Y0735976
X0320440Y0736031
X0315940Y0735924
X0311440Y0735831
X0317580Y0719996
X0333940Y0735895
X0329440Y0735814
X0324940Y0736067
X0275440Y0735626
X0243900Y0724662
X0325841Y0719731
X0240217Y0791695
X0240217Y0788695
X0271713Y0791695
X0271713Y0788695
X0299272Y0791695
X0318957Y0791695
X0291398Y0792234
X0311083Y0791871
X0307940Y0736445
X0303110Y0639381
X0297770Y0674720
X0305990Y0697189
X0311382Y0635432
X0241670Y0652558
X0293843Y0642536
X0278699Y0656491
X0280880Y0650295
X0316184Y0662630
X0269640Y0655290
X0270040Y0651241
X0266610Y0654171
X0277475Y0695723
X0236120Y0704173
X0295890Y0662662
X0287997Y0649064
X0294120Y0668391
X0274360Y0673831
X0269420Y0677062
X0293068Y0677108
X0279843Y0675688
X0265550Y0668415
X0289365Y0673719
X0289248Y0680521
X0261890Y0664761
X0275710Y0681593
X0267240Y0682519
X0278370Y0705093
X0266170Y0694826
X0273510Y0699749
X0286798Y0704143
X0324970Y0665128
X0327500Y0667244
X0334313Y0663113
X0333180Y0665611
X0293286Y0703504
X0313230Y0702465
X0267124Y0707892
X0259170Y0705138
X0269410Y0706003
X0316184Y0687630
X0332720Y0698170
X0314614Y0690767
X0316165Y0693404
X0331520Y0701642
X0332190Y0659883
X0332747Y0655636
X0332710Y0642694
X0326350Y0638968
X0328032Y0642674
X0320360Y0642275
X0295950Y0689520
X0284760Y0707022
X0301360Y0652183
X0302772Y0659604
X0300880Y0664296
X0297394Y0657033
X0292970Y0682450
X0289365Y0665845
X0251451Y0697465
X0239084Y0696252
X0279060Y0693306
X0275560Y0697804
X0272650Y0693742
X0272460Y0687889
X0306294Y0679156
X0306294Y0671156
X0306294Y0675156
X0243743Y0636514
X0246553Y0636684
X0256513Y0642494
X0249083Y0636664
X0252173Y0644344
X0256463Y0639364
X0254303Y0636744
X0254773Y0644424
X0251803Y0636704
X0305979Y0687156
X0306145Y0683156
X0305979Y0691156
X0234500Y0637685
X0238420Y0642148
X0243693Y0632254
X0317492Y0618193
X0329110Y0623514
X0320512Y0613603
X0298303Y0613184
X0311311Y0618197
X0308741Y0623871
X0323346Y0621930
X0327257Y0672408
X0310453Y0642451
X0273548Y0636471
X0273674Y0640095
X0273938Y0633084
X0263467Y0623638
X0261967Y0617638
X0269428Y0622966
X0263467Y0626638
X0261967Y0614638
X0297162Y0642065
X0302870Y0633981
X0314940Y0642067
X0306294Y0659156
X0304870Y0655747
X0327540Y0653432
X0265913Y0671772
X0252486Y0671772
X0239168Y0671672
X0250795Y0703150
X0279785Y0663876
X0279090Y0668504
X0306294Y0663156
X0306294Y0667156
X0278350Y0687309
X0292850Y0656359
X0301070Y0655920
X0330440Y0639504
X0326890Y0676159
X0324120Y0703114
X0237275Y0679609
X0244780Y0682521
X0249013Y0628514
X0236780Y0628738
X0317130Y0653628
X0305200Y0652883
X0307574Y0633762
X0314790Y0652049
X0320110Y0703093
X0299090Y0634421
X0237451Y0652761
X0240493Y0692678
X0253398Y0692357
X0257271Y0671772
X0249462Y0648383
X0265300Y0702131
X0270140Y0691038
X0269709Y0672575
X0270430Y0665576
X0288880Y0689467
X0289171Y0661908
X0301696Y0699351
X0299629Y0623877
X0317722Y0614646
X0314910Y0627222
X0320367Y0618071
X0328930Y0611691
X0307996Y0611536
X0312641Y0611556
X0301696Y0701851
X0246639Y0613778
X0246639Y0616378
X0246639Y0621778
X0246639Y0624378
X0243596Y0671772
X0305602Y0618185
X0305602Y0620685
X0308102Y0618185
X0308102Y0620685
X0322440Y0700130
X0297300Y0697221
X0329912Y0662383
X0296858Y0702544
X0328760Y0657144
X0326170Y0518386
X0320080Y0512736
X0295047Y0554565
X0280872Y0549841
X0290322Y0549841
X0274572Y0556142
X0239925Y0518339
X0239925Y0521489
X0239925Y0534087
X0239925Y0537236
X0235307Y0566357
X0243075Y0552984
X0268009Y0570953
X0271421Y0552985
X0280874Y0556139
X0236776Y0543536
X0236776Y0515190
X0328088Y0567503
X0332388Y0567703
X0330388Y0565803
X0332408Y0544097
X0277725Y0521493
X0261972Y0512040
X0265122Y0512040
X0261972Y0549836
X0265122Y0549836
X0246224Y0512040
X0249374Y0512040
X0249374Y0549835
X0239925Y0524639
X0239925Y0527788
X0325588Y0541447
X0328352Y0545412
X0328592Y0541146
X0324927Y0546013
X0321828Y0541682
X0318678Y0540966
X0329348Y0533403
X0304410Y0572782
X0263792Y0574203
X0320094Y0604114
X0236776Y0512040
X0301796Y0603917
X0259678Y0581553
X0315957Y0594127
X0261175Y0569054
X0252554Y0559314
X0243075Y0559284
X0249909Y0568653
X0242796Y0589749
X0243209Y0574018
X0246224Y0562434
X0246224Y0556134
X0245860Y0575049
X0285530Y0573002
X0274309Y0574653
X0246224Y0559284
X0269609Y0576413
X0279658Y0574443
X0236776Y0524639
X0236776Y0537236
X0236776Y0540386
X0236776Y0527788
X0236776Y0521489
X0323188Y0564503
X0323088Y0561503
X0260064Y0602993
X0261967Y0605638
X0261967Y0608638
X0268717Y0606015
X0323931Y0589733
X0239925Y0543536
X0239925Y0540386
X0252524Y0512040
X0255673Y0512040
X0252036Y0582131
X0255673Y0549835
X0252524Y0549835
X0271421Y0549836
X0268272Y0549836
X0271422Y0512040
X0268272Y0512040
X0277725Y0537241
X0277725Y0543541
X0277725Y0540391
X0277725Y0527792
X0277725Y0534092
X0253187Y0596382
X0269609Y0588653
X0273480Y0589201
X0278109Y0589238
X0283650Y0589044
X0236776Y0518339
X0236776Y0534087
X0306229Y0600263
X0310627Y0590232
X0310919Y0594040
X0313227Y0590232
X0313419Y0594040
X0242830Y0597415
X0239269Y0597128
X0242915Y0576539
X0245609Y0517182
X0249640Y0602519
X0249541Y0583156
X0253709Y0586128
X0249541Y0587156
X0249344Y0556134
X0249344Y0552984
X0255673Y0562431
X0255673Y0559282
X0255673Y0556133
X0255673Y0552984
X0255673Y0565580
X0252524Y0540387
X0249374Y0540387
X0255673Y0540387
X0252524Y0537237
X0249374Y0537237
X0255673Y0537237
X0249374Y0524639
X0249374Y0527789
X0255673Y0527789
X0255673Y0524639
X0249374Y0534088
X0252524Y0534088
X0255673Y0534088
X0252524Y0524639
X0252524Y0527789
X0271422Y0565583
X0265122Y0521489
X0261972Y0562431
X0262009Y0556153
X0261973Y0552985
X0271422Y0559291
X0271421Y0556135
X0271422Y0562434
X0268272Y0559291
X0265122Y0552985
X0274571Y0552985
X0284024Y0552989
X0287174Y0552989
X0284024Y0556139
X0280874Y0552989
X0287174Y0556139
X0277725Y0559289
X0277725Y0556135
X0280874Y0559289
X0277725Y0552989
X0284024Y0559289
X0284024Y0562438
X0280874Y0562438
X0287174Y0562438
X0290323Y0556140
X0290323Y0562439
X0290323Y0559289
X0287174Y0565588
X0284024Y0565588
X0290323Y0565589
X0290323Y0543541
X0290323Y0540391
X0287174Y0543541
X0287174Y0540391
X0284024Y0543541
X0280874Y0543541
X0280874Y0537241
X0284024Y0534092
X0287174Y0534092
X0280874Y0534092
X0290323Y0534092
X0299121Y0597542
X0291357Y0586128
X0293473Y0559290
X0293473Y0562439
X0293473Y0565589
X0293473Y0540391
X0293473Y0534092
X0301457Y0513837
X0296913Y0514460
X0318968Y0536052
X0307994Y0606886
X0319135Y0591407
X0313275Y0559590
X0329260Y0603381
X0313108Y0556556
X0313075Y0553755
X0313141Y0550821
X0313888Y0566003
X0313347Y0570695
X0316688Y0569603
X0316788Y0572903
X0312656Y0606881
X0287174Y0559289
X0291066Y0593088
X0291066Y0590488
X0268272Y0521489
X0261972Y0527789
X0261972Y0524639
X0265122Y0524639
X0265122Y0527789
X0268272Y0527789
X0268272Y0524639
X0261972Y0534088
X0265122Y0534088
X0268272Y0534088
X0261972Y0521489
X0261972Y0537237
X0268272Y0537237
X0265122Y0537237
X0261972Y0540387
X0265122Y0540387
X0268272Y0540387
X0246639Y0605778
X0246639Y0608378
X0323154Y0553867
X0323154Y0558867
X0323154Y0556367
X0322986Y0467109
X0330115Y0490303
X0324940Y0413899
X0329672Y0502057
X0326740Y0495763
X0278990Y0464793
X0305708Y0503043
X0263807Y0461234
X0334420Y0428660
X0328290Y0424304
X0254798Y0417728
X0258798Y0417594
X0246224Y0502591
X0290323Y0502595
X0280380Y0467284
X0321910Y0410139
X0331900Y0419317
X0284024Y0502595
X0263924Y0491754
X0265122Y0505741
X0254813Y0427018
X0279990Y0442071
X0276626Y0442913
X0279112Y0444954
X0282000Y0444966
X0273735Y0443034
X0271035Y0443051
X0275256Y0445753
X0331360Y0447306
X0327780Y0445819
X0329120Y0449203
X0326190Y0448621
X0287970Y0446705
X0292170Y0445986
X0291860Y0442927
X0288742Y0442090
X0286100Y0442298
X0283212Y0442286
X0289630Y0444828
X0286210Y0444926
X0265532Y0422648
X0318950Y0432473
X0278080Y0424760
X0274180Y0424966
X0280010Y0422279
X0281190Y0424966
X0269630Y0424884
X0271720Y0422587
X0276400Y0422341
X0266822Y0443297
X0317140Y0421775
X0238430Y0460338
X0252524Y0508891
X0252524Y0505741
X0249374Y0502591
X0255673Y0502591
X0249374Y0508891
X0261972Y0505741
X0257568Y0461513
X0249374Y0505741
X0243471Y0460292
X0261972Y0508891
X0265121Y0508891
X0309440Y0426404
X0300040Y0459733
X0331090Y0424304
X0255673Y0505741
X0251780Y0460883
X0322599Y0432505
X0243075Y0508891
X0308220Y0432552
X0307670Y0473605
X0319478Y0429389
X0246465Y0464893
X0243075Y0502591
X0261972Y0502591
X0252524Y0502591
X0255673Y0508891
X0300209Y0495853
X0297370Y0498563
X0277712Y0502595
X0288009Y0495653
X0287173Y0499445
X0271429Y0496295
X0271402Y0499441
X0274582Y0502591
X0303631Y0472607
X0315940Y0438104
X0315980Y0472128
X0280970Y0481197
X0303631Y0475607
X0313530Y0436460
X0307800Y0467859
X0277470Y0481197
X0287567Y0467649
X0287567Y0470649
X0252670Y0443592
X0275452Y0483219
X0241909Y0472553
X0237609Y0472453
X0235319Y0464362
X0251309Y0472553
X0246109Y0472465
X0255509Y0472253
X0269109Y0472353
X0264909Y0472553
X0260609Y0472453
X0273509Y0471649
X0321357Y0456709
X0321246Y0472669
X0280210Y0460762
X0316190Y0413299
X0325180Y0432577
X0325749Y0418701
X0236776Y0508891
X0268272Y0508891
X0268272Y0505741
X0267741Y0491608
X0265122Y0502591
X0262798Y0417886
X0284024Y0499445
X0282298Y0483803
X0276347Y0459741
X0303709Y0489353
X0301209Y0488853
X0316963Y0467655
X0316956Y0478833
X0325040Y0480129
X0276809Y0471853
X0240599Y0440053
X0244196Y0417010
X0244196Y0419610
X0244196Y0435610
X0244196Y0433010
X0244196Y0425010
X0244196Y0427610
X0291327Y0466811
X0284332Y0472834
X0306220Y0477125
X0301240Y0470885
X0311610Y0432528
X0310380Y0473942
X0307410Y0348380
X0262700Y0325494
X0285704Y0321809
X0272352Y0340900
X0288220Y0389630
X0274832Y0309687
X0272263Y0334222
X0289191Y0341348
X0270071Y0333021
X0303759Y0331478
X0275602Y0343811
X0262247Y0334502
X0267030Y0330147
X0280730Y0393856
X0318644Y0399643
X0321144Y0399643
X0323644Y0399643
X0326282Y0399743
X0262379Y0338103
X0275497Y0390758
X0319288Y0350376
X0323040Y0354485
X0275517Y0325842
X0272967Y0325842
X0253762Y0385255
X0272964Y0330669
X0323123Y0313589
X0315623Y0313589
X0318123Y0313589
X0320623Y0313589
X0313123Y0313589
X0310623Y0313589
X0276386Y0311687
X0270518Y0311637
X0264287Y0311687
X0253710Y0315669
X0258590Y0311560
X0267268Y0311642
X0250401Y0315713
X0264421Y0384812
X0288466Y0325343
X0327058Y0358376
X0270293Y0330540
X0239546Y0390528
X0279718Y0333694
X0239290Y0340428
X0261539Y0387755
X0297073Y0329159
X0236430Y0393470
X0236412Y0387722
X0241451Y0392147
X0266882Y0388165
X0311740Y0325839
X0254905Y0327213
X0295527Y0359812
X0281205Y0340997
X0247789Y0322910
X0309190Y0336959
X0321150Y0357730
X0285794Y0339063
X0262201Y0328491
X0269886Y0358753
X0270293Y0363972
X0277816Y0309678
X0281859Y0310862
X0245297Y0406029
X0252797Y0406029
X0250297Y0406029
X0247797Y0406029
X0305250Y0310342
X0301795Y0310398
X0287067Y0402358
X0240511Y0325517
X0240374Y0328960
X0244546Y0385315
X0247065Y0385398
X0272220Y0401343
X0265162Y0401391
X0243078Y0368384
X0256276Y0322652
X0281450Y0373151
X0247025Y0330512
X0319363Y0372149
X0321297Y0367739
X0322255Y0371935
X0321130Y0342418
X0333440Y0349221
X0333726Y0353801
X0263419Y0393450
X0286550Y0374402
X0238545Y0327149
X0279863Y0367513
X0267943Y0339617
X0255124Y0335244
X0282167Y0324242
X0238560Y0336136
X0299410Y0331201
X0237578Y0369584
X0270525Y0325754
X0263173Y0331794
X0240218Y0338010
X0254998Y0329779
X0278067Y0325842
X0306820Y0342146
X0282234Y0333792
X0295388Y0375644
X0277288Y0334282
X0318480Y0335039
X0240598Y0334642
X0256588Y0359005
X0244595Y0363535
X0305880Y0339046
X0286071Y0329184
X0260536Y0374216
X0246685Y0337357
X0251491Y0357134
X0277040Y0376172
X0270796Y0386643
X0264015Y0336151
X0314550Y0331564
X0238548Y0333149
X0270485Y0339030
X0285390Y0390550
X0310484Y0383312
X0333540Y0315590
X0313222Y0374229
X0298452Y0340487
X0254631Y0324716
X0299533Y0394056
X0305446Y0359450
X0265318Y0326487
X0267993Y0390695
X0239228Y0393291
X0256532Y0384895
X0247290Y0327694
X0261663Y0385193
X0273477Y0385100
X0284687Y0386769
X0281864Y0386178
X0288687Y0385290
X0291382Y0385457
X0291686Y0375177
X0303171Y0374224
X0319807Y0346376
X0313980Y0335813
X0237799Y0312598
X0293290Y0389737
X0286020Y0356454
X0309510Y0344127
X0236687Y0385234
X0238084Y0355992
X0241258Y0319123
X0250661Y0384780
X0246265Y0355855
X0259444Y0354291
X0255009Y0338318
X0247218Y0333049
X0245691Y0341215
X0270326Y0335795
X0274701Y0333804
X0261386Y0311687
X0269117Y0352876
X0263576Y0340898
X0268502Y0344181
X0281142Y0402379
X0283820Y0396266
X0276687Y0385100
X0280776Y0326412
X0294888Y0335326
X0294218Y0343587
X0294596Y0328129
X0294781Y0309788
X0298202Y0374572
X0315533Y0384749
X0307116Y0385979
X0314860Y0367656
X0309131Y0374573
X0319666Y0354376
X0319323Y0338320
X0322210Y0336696
X0322765Y0327721
X0319143Y0321928
X0316643Y0321928
X0314143Y0321928
X0311643Y0321928
X0309143Y0321928
X0321643Y0321928
X0315383Y0387863
X0303722Y0385367
X0295200Y0321473
X0293467Y0352442
X0294618Y0348287
X0285890Y0311357
X0279386Y0311687
X0281461Y0321744
X0283140Y0346082
X0281212Y0338079
X0275660Y0338857
X0286711Y0352668
X0282818Y0352687
X0277718Y0352687
X0278943Y0346914
X0290190Y0352480
X0267883Y0325837
X0262035Y0322679
X0247281Y0315727
X0250466Y0344381
X0254819Y0332435
X0248509Y0339207
X0251334Y0352857
X0240692Y0344204
X0243940Y0390885
X0332700Y0333089
X0269456Y0355353
X0240949Y0303148
X0239569Y0260639
X0239569Y0263639
X0246467Y0255442
X0249433Y0257697
X0259518Y0252358
X0241613Y0265197
X0259820Y0303800
X0257418Y0303533
X0274303Y0303413
X0266939Y0303281
X0264501Y0303109
X0258380Y0295984
X0247249Y0306298
X0244099Y0299998
X0240949Y0299998
X0240925Y0306257
X0276444Y0286183
X0278918Y0286887
X0273618Y0295387
X0281767Y0277742
X0269380Y0302736
X0276386Y0280407
X0273444Y0286183
X0281818Y0290787
X0267386Y0280407
X0265768Y0287546
X0279754Y0303269
X0268943Y0291086
X0279386Y0280407
X0262904Y0293850
X0270386Y0280407
X0270444Y0286183
X0261915Y0302033
X0303197Y0304297
X0300201Y0300874
X0265944Y0309640
X0274944Y0278363
X0268867Y0293942
X0296639Y0308057
X0307204Y0304212
X0265825Y0293987
X0277944Y0278363
X0261463Y0296111
X0240949Y0296848
X0237799Y0306298
X0257057Y0309636
X0234649Y0303148
X0237799Y0303148
X0269263Y0252800
X0266187Y0249852
X0311290Y0247249
X0301732Y0286867
X0298332Y0286867
X0257253Y0259197
X0270260Y0237037
X0254181Y0234521
X0279336Y0264795
X0254418Y0240407
X0278811Y0259135
X0237594Y0252754
X0292710Y0266542
X0281945Y0260231
X0301723Y0279150
X0300310Y0257242
X0286132Y0285953
X0256492Y0222466
X0241613Y0259197
X0279444Y0270543
X0273444Y0270543
X0305132Y0286867
X0272464Y0259964
X0263029Y0268139
X0271458Y0241347
X0282309Y0270435
X0237654Y0249719
X0297810Y0280709
X0279161Y0237817
X0254221Y0230582
X0239569Y0266639
X0300310Y0253842
X0257253Y0268197
X0296210Y0253187
X0247389Y0262139
X0267118Y0245587
X0257950Y0236924
X0276444Y0270543
X0242460Y0237591
X0255287Y0226709
X0263774Y0256464
X0263268Y0262370
X0299776Y0248010
X0282166Y0262922
X0241613Y0262197
X0296176Y0249585
X0260108Y0240376
X0294382Y0291966
X0257253Y0271197
X0256916Y0262609
X0249433Y0260697
X0249433Y0263697
X0312680Y0258353
X0263029Y0271139
X0272620Y0238653
X0260068Y0262187
X0256553Y0256881
X0301473Y0282650
X0300477Y0265010
X0301511Y0262204
X0241613Y0268197
X0268944Y0309643
X0272242Y0244842
X0236710Y0244042
X0247389Y0268139
X0276904Y0252550
X0269192Y0248209
X0267386Y0296047
X0282337Y0308217
X0290363Y0286082
X0247389Y0259139
X0301182Y0291966
X0244118Y0303187
X0273521Y0265849
X0277020Y0302298
X0241613Y0271197
X0239569Y0269639
X0254007Y0306819
X0244099Y0296848
X0247249Y0296848
X0253549Y0290548
X0250399Y0287398
X0244099Y0287398
X0257447Y0287117
X0250399Y0281098
X0254234Y0281622
X0244099Y0281098
X0237865Y0281131
X0234649Y0281098
X0240949Y0287398
X0240949Y0290548
X0237799Y0287398
X0240949Y0309448
X0237760Y0293692
X0244110Y0290505
X0328526Y0308696
X0260045Y0309615
X0315410Y0258656
X0311420Y0250230
X0239569Y0257639
X0244118Y0309387
X0262944Y0309643
X0271944Y0309643
X0264386Y0296047
X0282867Y0281142
X0282178Y0244005
X0294888Y0304456
X0297668Y0300709
X0295010Y0286767
X0297782Y0291966
X0294510Y0280709
X0295307Y0275439
X0295110Y0262961
X0331376Y0299883
X0300118Y0250987
X0295910Y0266706
X0285934Y0243931
X0290154Y0244007
X0278354Y0244281
X0276328Y0264687
X0288954Y0260788
X0281954Y0255588
X0283660Y0251542
X0286492Y0258364
X0289254Y0255688
X0286010Y0276042
X0280886Y0272587
X0277886Y0272587
X0269620Y0243240
X0271898Y0263173
X0271811Y0256687
X0263029Y0265139
X0265073Y0266697
X0263029Y0259139
X0268944Y0278363
X0268886Y0272587
X0265886Y0271718
X0271886Y0272587
X0270444Y0270543
X0273386Y0280407
X0274886Y0272587
X0265944Y0278363
X0264386Y0280407
X0271944Y0278363
X0262886Y0288227
X0271811Y0303313
X0244099Y0293698
X0250399Y0284248
X0244099Y0284248
X0250399Y0290548
X0247249Y0303148
X0254334Y0298728
X0255359Y0266557
X0255209Y0260639
X0244109Y0277996
X0255205Y0272755
X0257046Y0279607
X0240910Y0274742
X0237799Y0284248
X0237799Y0290548
X0237800Y0299998
X0339162Y0009304
X0276507Y0295816
X0253611Y0293765
X0250399Y0296848
X0267020Y0257079
X0349490Y0057698
X0397790Y0061360
X0367300Y0060442
X0376006Y0060991
X0383280Y0059940
X0361930Y0060031
X0366159Y0021822
X0397655Y0021336
X0381907Y0021507
X0401310Y0061439
X0389690Y0060665
X0339750Y0073383
X0353060Y0061504
X0323032Y0122237
X0313583Y0122387
X0299850Y0124708
X0299590Y0121289
X0365670Y0064458
X0373560Y0063973
X0383247Y0064141
X0363025Y0012926
X0370960Y0020577
X0371180Y0017789
X0410713Y0076187
X0408072Y0109146
X0334720Y0102184
X0337630Y0106304
X0376723Y0094178
X0392493Y0092647
X0331583Y0128717
X0353713Y0093057
X0345463Y0090837
X0302930Y0132994
X0376100Y0108780
X0384863Y0095437
X0372776Y0091746
X0378733Y0105987
X0264980Y0121886
X0269010Y0121648
X0340450Y0101914
X0354448Y0108092
X0404813Y0093887
X0401220Y0065155
X0358343Y0090948
X0391233Y0096093
X0407303Y0095117
X0404310Y0065213
X0390355Y0075775
X0367776Y0091746
X0362133Y0090877
X0343070Y0099372
X0344873Y0094847
X0354943Y0104191
X0361470Y0101757
X0399613Y0104657
X0380483Y0099047
X0249453Y0114307
X0391310Y0099570
X0369670Y0099845
X0340543Y0088647
X0335668Y0092822
X0382087Y0103647
X0400163Y0099177
X0352578Y0074292
X0392250Y0059899
X0346150Y0036030
X0346600Y0038561
X0389240Y0020548
X0392600Y0020548
X0397790Y0069610
X0388860Y0098010
X0374030Y0095000
X0351793Y0105404
X0344770Y0101718
X0391190Y0104173
X0336340Y0099265
X0398820Y0095823
X0379160Y0102923
X0384090Y0098743
X0372620Y0098355
X0362300Y0098674
X0409060Y0092095
X0391536Y0108990
X0399653Y0108357
X0389400Y0089232
X0397442Y0090667
X0399804Y0088778
X0384450Y0108830
X0373820Y0088400
X0380906Y0088134
X0360827Y0108541
X0359646Y0088174
X0366733Y0088477
X0404528Y0088702
X0332453Y0122297
X0293873Y0130357
X0259443Y0120773
X0343111Y0088429
X0350198Y0088277
X0336024Y0088176
X0339162Y0011904
X0339239Y0026832
X0339471Y0016773
X0339471Y0019373
X0339239Y0024232
X0336316Y0031815
X0358285Y0021325
X0350411Y0021277
X0382990Y0017519
X0379940Y0017789
X0399002Y0017519
X0356550Y0074767
X0393371Y0072919
X0403739Y0072783
X0414949Y0075291
X0259030Y0123727
X0401670Y0093807
X0253490Y0053736
X0249300Y0050862
X0245310Y0050867
X0241310Y0050983
X0237310Y0050983
X0246290Y0045504
X0250290Y0045504
X0242290Y0045504
X0326140Y0076196
X0323640Y0074393
X0312402Y0076587
X0316623Y0076047
X0321283Y0076327
X0309730Y0076232
X0307740Y0074263
X0314310Y0074540
X0318910Y0074595
X0295867Y0076567
X0302953Y0076167
X0299220Y0076196
X0305880Y0076361
X0292313Y0076345
X0278880Y0108482
X0276969Y0076247
X0281400Y0075938
X0285543Y0076867
X0289738Y0076173
X0279100Y0074447
X0283870Y0074724
X0287270Y0075018
X0287599Y0108831
X0268702Y0107928
X0268080Y0076416
X0272440Y0076177
X0269920Y0074318
X0274580Y0074281
X0257500Y0056117
X0258103Y0053688
X0287766Y0021289
X0274990Y0016396
X0284505Y0030676
X0268809Y0016400
X0278660Y0010073
X0265789Y0020990
X0262955Y0012663
X0266111Y0029229
X0393088Y0128455
X0248558Y0095038
X0324070Y0088861
X0311553Y0092347
X0317970Y0095961
X0278760Y0101061
X0287423Y0091857
X0303220Y0098397
X0351503Y0127972
X0271133Y0092787
X0343743Y0120967
X0398088Y0128455
X0256133Y0099347
X0263703Y0093847
X0327190Y0103818
X0289720Y0096094
X0327430Y0108208
X0312223Y0096407
X0242913Y0106157
X0296927Y0102991
X0320740Y0098599
X0293505Y0094965
X0237773Y0103607
X0272245Y0089585
X0325970Y0098817
X0263683Y0099902
X0239563Y0092077
X0351503Y0130972
X0291927Y0102991
X0315083Y0090207
X0243373Y0088767
X0253558Y0095038
X0310850Y0099620
X0378183Y0124904
X0325360Y0092517
X0262473Y0106937
X0252683Y0105867
X0421893Y0123537
X0367350Y0123927
X0235113Y0091307
X0296870Y0092072
X0330668Y0092822
X0281200Y0098369
X0301870Y0092072
X0276603Y0092119
X0273973Y0097645
X0365283Y0128125
X0274510Y0040553
X0272010Y0040553
X0327117Y0031840
X0317334Y0028955
X0323871Y0028812
X0323871Y0019812
X0323871Y0016812
X0323871Y0025812
X0322640Y0009774
X0317334Y0010955
X0323334Y0012377
X0280072Y0034330
X0277472Y0037459
X0277472Y0034959
X0275800Y0050212
X0275766Y0052772
X0235190Y0096905
X0323000Y0094337
X0327950Y0101057
X0302370Y0095215
X0295490Y0097209
X0286710Y0095717
X0279010Y0104889
X0264210Y0096914
X0247870Y0105821
X0294800Y0100593
X0265830Y0102566
X0239500Y0100925
X0273645Y0027712
X0285703Y0009813
X0391880Y0131692
X0399150Y0131773
X0351533Y0124697
X0377363Y0121108
X0367560Y0120823
X0421473Y0157556
X0421473Y0160556
X0434158Y0125092
X0434158Y0122272
X0433363Y0157607
X0433253Y0160737
X0329643Y0089887
X0321463Y0088517
X0312183Y0088837
X0302853Y0089057
X0296093Y0088477
X0286263Y0088677
X0277000Y0088323
X0287595Y0106109
X0261750Y0075886
X0267703Y0089397
X0246073Y0092197
X0256573Y0094097
X0236812Y0088698
X0240355Y0108757
X0344073Y0124397
X0282180Y0010253
X0265934Y0016522
X0258300Y0022289
X0268579Y0019365
X0278307Y0027707
X0278199Y0016408
X0280699Y0016408
X0278199Y0013908
X0280699Y0013908
X0273660Y0023037
X0278305Y0023057
X0257270Y0029334
X0295390Y0044017
X0295307Y0041260
X0287476Y0037125
X0295560Y0052907
X0295610Y0050299
X0322713Y0063167
X0326353Y0063167
X0318543Y0063167
X0310483Y0063167
X0314640Y0063167
X0298883Y0063167
X0303053Y0063167
X0306693Y0063167
X0294903Y0063167
X0277853Y0063167
X0282023Y0063167
X0290823Y0063167
X0269793Y0063167
X0273873Y0063167
X0245990Y0021219
X0241990Y0021219
X0249990Y0021219
X0241600Y0066317
X0237600Y0066317
X0249600Y0066317
X0245600Y0066317
X0253810Y0063244
X0265872Y0040782
X0268372Y0040782
X0351373Y0134367
X0243730Y0103057
X0236360Y0093931
X0314830Y0092851
X0405970Y0256489
X0405248Y0272731
X0427468Y0292287
X0427909Y0286759
X0423178Y0284601
X0402948Y0253251
X0367220Y0303202
X0404738Y0260421
X0403148Y0270191
X0401618Y0267351
X0394378Y0260501
X0392508Y0275581
X0393458Y0282931
X0398258Y0252341
X0421128Y0292601
X0427817Y0258829
X0399598Y0260251
X0399608Y0275211
X0420858Y0261331
X0426992Y0250016
X0418905Y0245694
X0398038Y0292571
X0336495Y0290569
X0403628Y0292201
X0418575Y0263691
X0421640Y0223403
X0428748Y0275222
X0421640Y0228403
X0424961Y0241203
X0418588Y0286681
X0428405Y0245194
X0421728Y0279141
X0426335Y0267062
X0371090Y0303487
X0370460Y0305908
X0369280Y0300916
X0353841Y0306194
X0341693Y0286010
X0422528Y0253531
X0364220Y0296795
X0373640Y0301078
X0374040Y0304980
X0365970Y0299194
X0334478Y0299604
X0340792Y0307107
X0351500Y0301795
X0354170Y0308924
X0401728Y0277251
X0405038Y0267521
X0405688Y0253581
X0354580Y0298101
X0426948Y0281051
X0428208Y0262109
X0422918Y0289501
X0418998Y0289871
X0418698Y0279631
X0418597Y0273538
X0422178Y0266891
X0419038Y0242611
X0405878Y0294071
X0418718Y0301181
X0427768Y0253569
X0342955Y0291523
X0345297Y0284849
X0357400Y0307608
X0271421Y0007319
X0396098Y0283931
X0392668Y0272511
X0391998Y0258251
X0399298Y0257231
X0399858Y0249711
X0422288Y0250661
X0422698Y0244301
X0400928Y0293151
X0395740Y0407528
X0372080Y0330574
X0369934Y0322946
X0384248Y0319157
X0336720Y0310846
X0346020Y0374075
X0362540Y0361443
X0382190Y0388077
X0364580Y0391273
X0379750Y0383965
X0364880Y0384455
X0390080Y0331575
X0382680Y0408202
X0379720Y0372257
X0352420Y0375672
X0379560Y0374955
X0364645Y0377065
X0379286Y0378015
X0354690Y0377000
X0379300Y0380862
X0343770Y0382166
X0376600Y0408045
X0382620Y0391882
X0344720Y0325739
X0341910Y0325739
X0369040Y0316735
X0411240Y0316482
X0408790Y0317049
X0339370Y0329176
X0339600Y0332076
X0336850Y0380332
X0349110Y0375767
X0343880Y0356989
X0399880Y0319568
X0343430Y0385937
X0378830Y0386352
X0337293Y0316660
X0353903Y0314077
X0356835Y0313894
X0365026Y0332478
X0360350Y0395873
X0366140Y0407639
X0389740Y0404725
X0360960Y0389080
X0359410Y0317080
X0334816Y0372609
X0357110Y0329210
X0357040Y0332970
X0359120Y0331164
X0337330Y0372679
X0337316Y0367758
X0362660Y0316986
X0334816Y0367787
X0371080Y0481589
X0369507Y0464391
X0376540Y0498385
X0378910Y0430874
X0354750Y0445325
X0343420Y0497966
X0340902Y0503742
X0354565Y0451562
X0348870Y0501571
X0381239Y0467171
X0375190Y0463996
X0335162Y0502791
X0413607Y0485620
X0410607Y0485620
X0401556Y0508937
X0428747Y0468770
X0336740Y0417069
X0414870Y0450976
X0414870Y0455166
X0419420Y0453168
X0419420Y0457358
X0429670Y0449552
X0422460Y0449467
X0425870Y0449509
X0433720Y0449467
X0422080Y0410454
X0422080Y0414644
X0432960Y0414886
X0422120Y0418288
X0432450Y0418766
X0430340Y0416573
X0422760Y0445581
X0421710Y0424527
X0421770Y0433187
X0422860Y0441790
X0351650Y0420270
X0348220Y0486484
X0345270Y0452745
X0339506Y0482841
X0338762Y0479636
X0346750Y0466532
X0389670Y0477262
X0386410Y0477576
X0388890Y0480439
X0385940Y0482478
X0351250Y0499752
X0352160Y0502138
X0353460Y0504536
X0353400Y0507260
X0387080Y0486400
X0352260Y0483029
X0348000Y0479150
X0352890Y0479656
X0365850Y0414874
X0371260Y0412879
X0393370Y0411618
X0369500Y0445873
X0372710Y0445705
X0368660Y0449478
X0371080Y0448276
X0371950Y0430527
X0372320Y0439514
X0388982Y0496939
X0402458Y0505903
X0406352Y0471405
X0428747Y0463314
X0405348Y0506316
X0413222Y0508054
X0413138Y0504813
X0355250Y0420679
X0346862Y0424850
X0392076Y0470970
X0374207Y0479329
X0374203Y0491029
X0409985Y0508431
X0381760Y0496004
X0383750Y0437058
X0336218Y0424850
X0376150Y0430405
X0373850Y0496585
X0374560Y0412421
X0369280Y0415600
X0368787Y0472998
X0377284Y0473374
X0374203Y0482079
X0355150Y0486758
X0412260Y0482881
X0409054Y0483084
X0389107Y0492097
X0413733Y0499781
X0410733Y0499781
X0413733Y0496781
X0410733Y0496781
X0413733Y0493781
X0410733Y0493781
X0407733Y0499781
X0407733Y0496781
X0407733Y0493781
X0419071Y0509283
X0407733Y0490781
X0410733Y0490781
X0413733Y0490781
X0336088Y0454511
X0368943Y0506356
X0402900Y0444842
X0405930Y0411386
X0405980Y0414630
X0406000Y0444755
X0406200Y0417755
X0403130Y0418091
X0399050Y0450968
X0399060Y0454322
X0398800Y0458058
X0398800Y0462248
X0406530Y0440667
X0406150Y0433203
X0406140Y0424766
X0335860Y0516486
X0346350Y0517286
X0350902Y0512520
X0341512Y0512429
X0352940Y0518025
X0350690Y0516376
X0342190Y0565848
X0369848Y0588903
X0369918Y0592253
X0373518Y0592403
X0373448Y0589053
X0431520Y0607039
X0357820Y0534561
X0341011Y0537828
X0393596Y0567630
X0424873Y0513921
X0425999Y0516211
X0399590Y0553502
X0431145Y0556608
X0421461Y0547703
X0405954Y0532502
X0413342Y0556219
X0408736Y0551529
X0423861Y0556535
X0428039Y0556539
X0434187Y0556444
X0396470Y0527847
X0340330Y0541931
X0353120Y0510003
X0348190Y0511550
X0354973Y0602588
X0354973Y0605588
X0360647Y0602636
X0351964Y0599332
X0376528Y0520138
X0373538Y0520213
X0382333Y0540414
X0382596Y0537379
X0376490Y0540574
X0377150Y0543151
X0370309Y0550322
X0379733Y0549392
X0368825Y0539776
X0394389Y0604053
X0412783Y0605500
X0429340Y0596874
X0396558Y0522251
X0434203Y0542897
X0416515Y0547602
X0396590Y0549310
X0428039Y0548119
X0422050Y0517028
X0408486Y0537333
X0407776Y0527426
X0407865Y0516627
X0411439Y0516956
X0383617Y0517862
X0417979Y0545352
X0426068Y0546048
X0412088Y0521721
X0409251Y0521763
X0406881Y0591322
X0406884Y0594176
X0358182Y0531231
X0351110Y0531835
X0336010Y0531598
X0340182Y0531787
X0385410Y0566122
X0395922Y0536127
X0396048Y0540127
X0404336Y0545280
X0431356Y0516836
X0431280Y0514223
X0396520Y0567444
X0420883Y0556729
X0395690Y0512774
X0396350Y0532016
X0404578Y0551838
X0390000Y0567345
X0424904Y0586283
X0425151Y0608429
X0401422Y0597270
X0398386Y0587126
X0401091Y0587054
X0398822Y0600399
X0401422Y0599770
X0336057Y0575657
X0368238Y0522673
X0383924Y0514797
X0417520Y0531177
X0417617Y0536773
X0428874Y0530627
X0423332Y0536763
X0428745Y0536999
X0417520Y0525128
X0428874Y0525193
X0423278Y0525160
X0368694Y0546159
X0365329Y0546121
X0382595Y0554166
X0384485Y0552365
X0402499Y0554143
X0391630Y0597900
X0383344Y0593262
X0383344Y0590662
X0413022Y0593947
X0410522Y0593947
X0422210Y0605343
X0382632Y0532822
X0382632Y0527822
X0382632Y0530322
X0384588Y0526069
X0385040Y0521754
X0379177Y0509798
X0366426Y0532722
X0366426Y0530222
X0366426Y0527722
X0339616Y0605938
X0339616Y0603438
X0342759Y0599193
X0400587Y0607022
X0405249Y0607017
X0337550Y0553618
X0337550Y0556118
X0337550Y0558618
X0390950Y0701922
X0398620Y0701411
X0399873Y0666411
X0382580Y0637413
X0373218Y0634217
X0389856Y0645705
X0411149Y0678387
X0429820Y0656709
X0351730Y0649206
X0376946Y0689985
X0363530Y0629727
X0390660Y0686923
X0347670Y0642285
X0414810Y0696968
X0367520Y0701710
X0342230Y0709384
X0338926Y0697752
X0339010Y0700406
X0345580Y0638109
X0421350Y0694003
X0427210Y0691934
X0425590Y0695895
X0339750Y0695271
X0423242Y0707949
X0335130Y0670744
X0426391Y0701173
X0340870Y0665042
X0427230Y0707377
X0365090Y0676923
X0364765Y0687963
X0338970Y0670776
X0364115Y0692990
X0364649Y0684022
X0337798Y0686721
X0336110Y0693934
X0361760Y0668716
X0351720Y0670018
X0365160Y0672922
X0340530Y0675658
X0351730Y0663450
X0340630Y0655093
X0348480Y0638558
X0365380Y0668972
X0337070Y0639759
X0335610Y0658177
X0340669Y0644827
X0377100Y0697218
X0399363Y0653588
X0411065Y0667516
X0379462Y0666156
X0410085Y0618329
X0401353Y0624007
X0361660Y0671306
X0362040Y0684875
X0361510Y0680886
X0363590Y0702324
X0361580Y0703860
X0430813Y0687156
X0430862Y0691156
X0430813Y0695156
X0430731Y0707156
X0430667Y0703156
X0430618Y0699156
X0354973Y0611588
X0354973Y0623588
X0354973Y0620588
X0354973Y0614588
X0361473Y0620588
X0377669Y0706237
X0414318Y0700979
X0377679Y0701168
X0403904Y0618333
X0391447Y0611973
X0413105Y0613739
X0416454Y0621319
X0377681Y0694244
X0406100Y0631851
X0394380Y0643389
X0379461Y0675246
X0376089Y0646156
X0379492Y0650239
X0361580Y0652755
X0361562Y0645175
X0361650Y0658537
X0422026Y0656883
X0426100Y0667884
X0422222Y0675226
X0412250Y0683196
X0422981Y0690351
X0414550Y0707464
X0423055Y0696713
X0351722Y0659319
X0376650Y0654157
X0379093Y0657739
X0410918Y0649363
X0423623Y0645396
X0422007Y0652732
X0353260Y0688757
X0367614Y0693053
X0367496Y0690248
X0353902Y0667128
X0377211Y0673197
X0392097Y0676231
X0391938Y0672320
X0386173Y0665065
X0379791Y0679454
X0367480Y0705169
X0351810Y0706800
X0400408Y0681193
X0430861Y0679156
X0427900Y0679709
X0376087Y0670156
X0391740Y0705957
X0392080Y0692796
X0403970Y0642364
X0391910Y0696742
X0363340Y0650512
X0364980Y0655266
X0365620Y0663069
X0361810Y0675011
X0364320Y0680434
X0396150Y0708926
X0335390Y0667895
X0411675Y0672654
X0413643Y0680004
X0412878Y0693183
X0400968Y0686699
X0335915Y0675011
X0367066Y0681094
X0399829Y0690191
X0411862Y0688027
X0337030Y0677894
X0413718Y0655267
X0383034Y0640267
X0417422Y0637592
X0414760Y0636225
X0409520Y0637387
X0399440Y0637340
X0395701Y0637430
X0420245Y0636004
X0340340Y0638054
X0368100Y0668133
X0367870Y0650239
X0373680Y0662417
X0421080Y0665945
X0411982Y0660285
X0365990Y0645272
X0415218Y0664203
X0414183Y0686151
X0368200Y0672132
X0399223Y0644930
X0425334Y0656419
X0413966Y0675624
X0432180Y0647458
X0396366Y0653229
X0396550Y0680266
X0413535Y0646804
X0353298Y0633903
X0362173Y0665128
X0422221Y0619873
X0340525Y0686600
X0339930Y0661219
X0365070Y0658065
X0371407Y0641507
X0385573Y0629998
X0413930Y0639810
X0417974Y0663446
X0361646Y0689228
X0392063Y0624109
X0419221Y0612253
X0410315Y0614782
X0405426Y0626809
X0412960Y0618207
X0367858Y0657573
X0380101Y0660239
X0396940Y0658078
X0399911Y0661325
X0410989Y0652957
X0422470Y0647852
X0396478Y0661529
X0430140Y0665660
X0425146Y0672426
X0367866Y0677326
X0367399Y0684652
X0389961Y0682218
X0390000Y0689724
X0425173Y0688588
X0430873Y0684536
X0361717Y0695128
X0361786Y0699128
X0423317Y0705344
X0433872Y0645119
X0400267Y0684029
X0415834Y0693272
X0339384Y0611544
X0339384Y0614144
X0339600Y0618693
X0339600Y0621293
X0400589Y0611672
X0405234Y0611692
X0400695Y0620821
X0398195Y0618321
X0400695Y0618321
X0398195Y0620821
X0364844Y0698332
X0351728Y0653860
X0422510Y0677836
X0394840Y0711437
X0400730Y0721954
X0406720Y0723395
X0376190Y0711259
X0352010Y0713968
X0415730Y0710897
X0341190Y0712379
X0431440Y0723955
X0417330Y0717420
X0414080Y0721334
X0372110Y0720308
X0426440Y0724240
X0424410Y0718429
X0429240Y0721014
X0376770Y0734898
X0412080Y0719034
X0377840Y0724388
X0421730Y0717398
X0366860Y0739956
X0354060Y0734790
X0424200Y0733399
X0409010Y0726147
X0345610Y0733982
X0427130Y0717871
X0373500Y0748457
X0342230Y0720936
X0338460Y0724585
X0364750Y0727821
X0363460Y0735388
X0338270Y0733387
X0357830Y0718682
X0375834Y0727459
X0339300Y0716800
X0357610Y0748302
X0375548Y0731459
X0430738Y0711156
X0402540Y0710649
X0367350Y0713661
X0382960Y0711431
X0371170Y0711574
X0426900Y0779752
X0428250Y0772054
X0354420Y0749198
X0350720Y0745722
X0354520Y0728701
X0352400Y0722132
X0423900Y0736055
X0417880Y0786361
X0415780Y0747078
X0367904Y0778327
X0364090Y0748565
X0363300Y0781303
X0360160Y0775523
X0354870Y0771388
X0350450Y0784982
X0344710Y0785782
X0337800Y0774677
X0421690Y0779548
X0334640Y0725035
X0420290Y0733741
X0361490Y0712505
X0413940Y0735665
X0418440Y0735930
X0360246Y0730819
X0357096Y0732976
X0350580Y0724427
X0366430Y0731459
X0363359Y0743537
X0370430Y0749138
X0417384Y0791476
X0421321Y0791476
X0346516Y0790294
X0366201Y0790976
X0354390Y0790294
X0350180Y0735880
X0343730Y0724581
X0344780Y0713349
X0389350Y0711288
X0409581Y0711643
X0336990Y0735701
X0376960Y0791580
X0376960Y0788580
X0366201Y0787976
X0375575Y0739459
X0363162Y0739537
X0361350Y0720720
X0366510Y0723622
X0426430Y0735126
X0430940Y0735895
X0420160Y0724309
X0422940Y0723802
X0514498Y0716473
X0522865Y0711178
X0517775Y0711203
X0454070Y0714226
X0451820Y0712210
X0460822Y0712620
X0473940Y0714184
X0466620Y0714137
X0477710Y0722299
X0531029Y0733142
X0447680Y0733564
X0480620Y0734244
X0439200Y0722093
X0532940Y0734810
X0528388Y0722903
X0524576Y0733227
X0501604Y0733003
X0451320Y0725044
X0514420Y0733131
X0450410Y0733682
X0442120Y0724781
X0521800Y0732667
X0500260Y0729094
X0457060Y0722427
X0509855Y0724107
X0455410Y0734113
X0476160Y0734205
X0516940Y0735683
X0476980Y0736594
X0465850Y0733428
X0449060Y0721761
X0440660Y0712065
X0488090Y0710545
X0490890Y0714898
X0488180Y0719244
X0517443Y0717011
X0499452Y0714582
X0499842Y0710582
X0471780Y0786300
X0453960Y0723142
X0512610Y0747115
X0444370Y0770152
X0533600Y0778780
X0510608Y0717448
X0519440Y0772861
X0504440Y0772548
X0525110Y0774395
X0499270Y0776431
X0514620Y0713193
X0444530Y0723917
X0441006Y0785297
X0511770Y0779940
X0473560Y0724951
X0501890Y0746663
X0446260Y0722014
X0529300Y0771341
X0512548Y0722093
X0507935Y0785704
X0495110Y0771733
X0491720Y0776713
X0485870Y0776087
X0480770Y0778125
X0498080Y0733252
X0454120Y0785923
X0470550Y0724034
X0463750Y0780452
X0434540Y0778500
X0461565Y0785806
X0459950Y0722720
X0442650Y0719485
X0466440Y0724465
X0471310Y0733811
X0436440Y0724710
X0462440Y0735687
X0466440Y0735987
X0494850Y0733252
X0518500Y0723073
X0474940Y0747192
X0515809Y0791476
X0519746Y0791476
X0496124Y0791476
X0500061Y0791476
X0476439Y0791476
X0480376Y0791476
X0456754Y0791476
X0460691Y0791476
X0437069Y0791476
X0441006Y0791476
X0446900Y0714648
X0506105Y0724132
X0523370Y0724131
X0514901Y0724120
X0531845Y0724095
X0491890Y0735740
X0487940Y0735681
X0483180Y0736506
X0496000Y0736152
X0512140Y0736554
X0528440Y0735681
X0519440Y0735681
X0458050Y0725053
X0471450Y0736368
X0435440Y0735928
X0443940Y0735681
X0439940Y0735507
X0453530Y0736212
X0447240Y0724780
X0502890Y0736349
X0490040Y0622140
X0532479Y0633588
X0434681Y0642639
X0444458Y0669350
X0445270Y0660832
X0476320Y0629280
X0475820Y0635422
X0458820Y0674137
X0447161Y0673564
X0498350Y0627580
X0518920Y0615387
X0445604Y0629045
X0487832Y0624429
X0502080Y0622999
X0484700Y0660355
X0501940Y0644073
X0526300Y0623621
X0492770Y0665090
X0459690Y0626423
X0462270Y0612911
X0448460Y0625960
X0532420Y0615484
X0437120Y0612933
X0523800Y0611145
X0458903Y0644884
X0530779Y0637354
X0468540Y0655799
X0527111Y0686052
X0493020Y0646701
X0518947Y0685122
X0480310Y0642224
X0469229Y0638135
X0473294Y0613207
X0439250Y0630973
X0494340Y0691623
X0514320Y0641085
X0504295Y0649612
X0508061Y0645381
X0496690Y0633589
X0510700Y0634300
X0501120Y0633249
X0517888Y0687901
X0444700Y0651900
X0490120Y0662703
X0521516Y0650576
X0506409Y0691373
X0517328Y0655529
X0501540Y0681970
X0526600Y0679117
X0496277Y0678185
X0505580Y0679105
X0515429Y0697278
X0529899Y0661020
X0505690Y0654419
X0515429Y0692278
X0526430Y0664730
X0525692Y0654862
X0533270Y0679351
X0497320Y0665216
X0504241Y0665809
X0529525Y0669349
X0501914Y0675624
X0506092Y0697575
X0481253Y0654837
X0531599Y0689838
X0531597Y0697509
X0496577Y0684553
X0496453Y0670876
X0504114Y0670830
X0506470Y0683512
X0440688Y0694438
X0495560Y0694781
X0479512Y0649436
X0481227Y0696366
X0481227Y0691366
X0490900Y0706145
X0440688Y0689438
X0440690Y0702386
X0497350Y0699767
X0520370Y0625158
X0515541Y0661845
X0527828Y0615387
X0508024Y0613598
X0443850Y0634754
X0491167Y0687507
X0491380Y0694656
X0491067Y0699656
X0500710Y0706582
X0508400Y0617803
X0504980Y0616425
X0481227Y0685366
X0440688Y0684438
X0479354Y0677054
X0468810Y0652180
X0495900Y0641804
X0491380Y0639279
X0511910Y0638722
X0435972Y0655595
X0474946Y0659376
X0436445Y0667628
X0435539Y0671628
X0491060Y0671604
X0491044Y0667604
X0479409Y0682305
X0483056Y0679628
X0492294Y0682347
X0465580Y0641417
X0482180Y0646278
X0492310Y0650516
X0503680Y0659666
X0504836Y0657097
X0531970Y0650491
X0506376Y0687436
X0498870Y0668324
X0498040Y0675306
X0526610Y0672286
X0436000Y0675706
X0518800Y0665776
X0515438Y0649996
X0518382Y0678247
X0517222Y0673917
X0517806Y0670102
X0468260Y0664366
X0469977Y0676496
X0446500Y0645075
X0463178Y0647483
X0469467Y0679915
X0437100Y0643793
X0447210Y0665143
X0464050Y0633877
X0464330Y0663251
X0505780Y0642543
X0463020Y0661023
X0530012Y0708618
X0457138Y0663251
X0466980Y0667059
X0461997Y0654507
X0460587Y0669424
X0482544Y0668042
X0482398Y0673087
X0458650Y0666543
X0473153Y0622451
X0453935Y0624739
X0440135Y0615808
X0461960Y0684394
X0519830Y0634663
X0470190Y0648693
X0446980Y0638774
X0444403Y0665963
X0466049Y0675327
X0479353Y0668666
X0478905Y0659426
X0456960Y0685581
X0491100Y0644351
X0446799Y0657526
X0456342Y0649436
X0495622Y0660178
X0491930Y0654203
X0498666Y0653012
X0515371Y0658880
X0491157Y0675604
X0457730Y0682010
X0459650Y0685993
X0460530Y0681874
X0463120Y0681992
X0494323Y0687669
X0491189Y0679656
X0515425Y0685783
X0437509Y0648996
X0435420Y0647117
X0469890Y0596580
X0481340Y0593296
X0468740Y0585897
X0489800Y0600200
X0490600Y0608136
X0503338Y0544825
X0503338Y0549825
X0501331Y0528932
X0489962Y0540849
X0490661Y0547148
X0525338Y0540125
X0528138Y0539925
X0500338Y0566425
X0500338Y0569425
X0504613Y0525200
X0516380Y0540364
X0521938Y0540325
X0534401Y0529562
X0500138Y0558625
X0500538Y0572025
X0513738Y0562425
X0500419Y0578644
X0520228Y0590335
X0524638Y0590225
X0530338Y0590325
X0505738Y0590525
X0516738Y0562425
X0494238Y0600441
X0500538Y0600925
X0500138Y0563025
X0500438Y0574925
X0518938Y0540425
X0446378Y0582681
X0450778Y0583106
X0530438Y0529525
X0447830Y0588739
X0441230Y0587341
X0500538Y0588525
X0514058Y0605055
X0529408Y0603485
X0440040Y0608537
X0439762Y0515540
X0449402Y0515514
X0453700Y0545047
X0450367Y0540720
X0453917Y0550069
X0434605Y0521488
X0463031Y0543563
X0447781Y0523888
X0448329Y0534995
X0441063Y0540563
X0438722Y0538842
X0454022Y0541052
X0442240Y0553337
X0519430Y0511801
X0514430Y0511801
X0483838Y0561148
X0483838Y0556148
X0483838Y0566194
X0483838Y0571194
X0490738Y0587125
X0485738Y0587125
X0483209Y0550250
X0471804Y0556085
X0483209Y0545250
X0471804Y0561085
X0435319Y0600123
X0456722Y0529536
X0437832Y0556374
X0435998Y0539726
X0441326Y0556050
X0439762Y0523757
X0453854Y0555069
X0452895Y0510061
X0451325Y0525981
X0445838Y0538085
X0463991Y0531504
X0450540Y0521331
X0442763Y0549595
X0503958Y0529405
X0498920Y0523803
X0485510Y0536673
X0515413Y0590950
X0527638Y0590325
X0509238Y0608515
X0500098Y0608885
X0525570Y0602466
X0451504Y0529734
X0463565Y0515723
X0466587Y0515764
X0467496Y0513179
X0467677Y0510055
X0455890Y0592792
X0471190Y0593964
X0485380Y0596505
X0460236Y0581679
X0453775Y0600614
X0458600Y0599200
X0437516Y0587579
X0474290Y0563565
X0474130Y0553659
X0486640Y0543687
X0481380Y0553210
X0486720Y0563730
X0481410Y0573563
X0489380Y0590839
X0485890Y0590563
X0511560Y0513792
X0522250Y0513692
X0515110Y0528785
X0513480Y0541499
X0533038Y0590325
X0527438Y0600325
X0523538Y0600325
X0519638Y0600425
X0513838Y0556925
X0530638Y0539525
X0519438Y0543025
X0505718Y0542865
X0504613Y0522050
X0523938Y0528725
X0503448Y0540235
X0512354Y0590825
X0504268Y0608625
X0496140Y0608883
X0500138Y0543225
X0500038Y0550725
X0500038Y0555925
X0489938Y0563425
X0490538Y0567825
X0510338Y0571325
X0490693Y0570770
X0487398Y0576665
X0490658Y0579025
X0499868Y0585725
X0527138Y0529525
X0505738Y0600425
X0530940Y0422207
X0438520Y0452324
X0438390Y0456129
X0446950Y0417162
X0446660Y0413325
X0439830Y0410374
X0444020Y0410374
X0444850Y0446337
X0436370Y0410543
X0436710Y0446260
X0440900Y0446260
X0439749Y0506523
X0497818Y0440265
X0524938Y0493125
X0519938Y0493125
X0522379Y0431974
X0523667Y0438452
X0529028Y0430469
X0498119Y0470011
X0529968Y0440216
X0533038Y0488323
X0525638Y0484023
X0506230Y0499059
X0511230Y0499059
X0481300Y0422150
X0482880Y0462935
X0480118Y0474107
X0482880Y0467935
X0480118Y0479107
X0506456Y0446928
X0527300Y0417368
X0526440Y0422428
X0495500Y0447465
X0523838Y0442723
X0516353Y0443517
X0505843Y0465018
X0486300Y0422150
X0525603Y0480187
X0502938Y0463823
X0509486Y0433829
X0490334Y0497342
X0517929Y0439676
X0512867Y0443679
X0437716Y0476295
X0447770Y0485290
X0444920Y0485259
X0494980Y0482979
X0492260Y0482826
X0450813Y0492993
X0445199Y0494590
X0454770Y0495587
X0457537Y0495546
X0463540Y0495717
X0466307Y0495676
X0445366Y0490657
X0467586Y0506807
X0529910Y0419478
X0461540Y0449833
X0505740Y0495880
X0511520Y0496255
X0480050Y0419556
X0486670Y0426196
X0437887Y0471073
X0479754Y0462988
X0505442Y0458719
X0509464Y0450265
X0502494Y0436725
X0483641Y0479628
X0483685Y0473522
X0479575Y0467597
X0516353Y0480708
X0515780Y0434039
X0526440Y0432077
X0533040Y0453221
X0530038Y0444323
X0531440Y0432178
X0511070Y0493380
X0525698Y0496724
X0519490Y0496645
X0532934Y0491384
X0533740Y0465021
X0533740Y0458021
X0533740Y0473021
X0526340Y0452321
X0519440Y0452321
X0513140Y0452621
X0513140Y0466021
X0513140Y0459721
X0513140Y0473021
X0519640Y0473021
X0525640Y0473021
X0499551Y0429636
X0450899Y0483452
X0463702Y0475480
X0454702Y0475480
X0460702Y0475480
X0457702Y0475480
X0466702Y0475480
X0502687Y0417453
X0498238Y0417825
X0510577Y0417741
X0505819Y0417473
X0514820Y0417617
X0517617Y0422944
X0461590Y0446700
X0465790Y0446700
X0465730Y0449833
X0472210Y0450267
X0473140Y0439971
X0467920Y0451667
X0463690Y0451813
X0471540Y0437214
X0469500Y0447730
X0461080Y0411451
X0465270Y0411451
X0469530Y0411451
X0474080Y0411451
X0527603Y0337208
X0527438Y0340353
X0531430Y0337074
X0531795Y0340409
X0520510Y0337299
X0509140Y0338005
X0514400Y0340829
X0480830Y0333921
X0528680Y0317349
X0526250Y0310940
X0518590Y0310129
X0511070Y0310719
X0523930Y0321642
X0517260Y0315978
X0522420Y0315475
X0519650Y0320384
X0445900Y0403460
X0446830Y0400551
X0443240Y0401984
X0439150Y0400930
X0451950Y0402434
X0438340Y0403375
X0448970Y0403846
X0475190Y0339013
X0470090Y0332824
X0465883Y0399834
X0465913Y0402659
X0502111Y0388567
X0497111Y0388567
X0464810Y0311253
X0484780Y0314090
X0494850Y0315733
X0468210Y0401505
X0495140Y0385762
X0504897Y0390481
X0461130Y0408318
X0465330Y0408318
X0469590Y0408318
X0474140Y0408318
X0528105Y0230594
X0498867Y0227773
X0492700Y0223800
X0504941Y0227859
X0459990Y0245930
X0471795Y0267941
X0487168Y0214568
X0524405Y0212531
X0453810Y0289325
X0445890Y0283317
X0442520Y0223623
X0452900Y0281647
X0443212Y0240957
X0441792Y0259473
X0484169Y0272867
X0441580Y0250730
X0456530Y0256034
X0525480Y0268959
X0504160Y0255584
X0534208Y0227832
X0530119Y0280101
X0517670Y0247527
X0532794Y0282068
X0515675Y0254098
X0449860Y0272121
X0449860Y0267121
X0459108Y0253181
X0507000Y0239000
X0478000Y0212500
X0517189Y0226229
X0524675Y0234766
X0515675Y0234555
X0512160Y0217073
X0499405Y0242877
X0491320Y0231809
X0445540Y0288853
X0451790Y0300129
X0453620Y0245162
X0441498Y0266731
X0456800Y0259233
X0516551Y0214987
X0496123Y0233500
X0516625Y0230075
X0519300Y0220500
X0447900Y0265292
X0449290Y0276227
X0453780Y0292411
X0441076Y0294906
X0442165Y0271284
X0454150Y0249053
X0450576Y0234431
X0488816Y0242877
X0486738Y0210434
X0457165Y0262368
X0519183Y0224173
X0498875Y0217172
X0529527Y0265584
X0441361Y0300812
X0442148Y0279361
X0442580Y0236459
X0499075Y0235575
X0533474Y0196500
X0526621Y0177079
X0516100Y0178100
X0512200Y0196000
X0470324Y0133424
X0476400Y0203100
X0468400Y0135800
X0466200Y0207300
X0471300Y0201900
X0473200Y0140300
X0523593Y0198171
X0494210Y0175035
X0502999Y0180541
X0488850Y0175419
X0475770Y0186451
X0482980Y0181071
X0496360Y0167221
X0489040Y0169483
X0493670Y0171871
X0505580Y0192555
X0462790Y0183489
X0494467Y0148867
X0500215Y0136449
X0492424Y0142234
X0488570Y0147486
X0521320Y0178184
X0515600Y0172800
X0522111Y0113310
X0527613Y0113373
X0520015Y0194584
X0509100Y0191900
X0515231Y0191334
X0516146Y0113121
X0509691Y0112938
X0529592Y0192999
X0461880Y0150596
X0504750Y0111749
X0490130Y0163086
X0486370Y0189279
X0480220Y0185766
X0487080Y0180918
X0482500Y0184169
X0525293Y0191705
X0514500Y0194300
X0514766Y0208222
X0506234Y0207368
X0526443Y0194116
X0510000Y0173500
X0518640Y0125539
X0498940Y0179744
X0487020Y0119754
X0497430Y0124024
X0488220Y0157515
X0501040Y0177297
X0509710Y0127269
X0474630Y0174843
X0468452Y0197934
X0472670Y0166398
X0475760Y0168747
X0473950Y0172124
X0473580Y0177859
X0450650Y0203785
X0547480Y0096632
X0565938Y0096820
X0542180Y0093534
X0529272Y0178311
X0512600Y0178900
X0499154Y0194198
X0512200Y0204200
X0526657Y0207363
X0532500Y0206500
X0446522Y0146932
X0488017Y0203716
X0610543Y0107678
X0444550Y0184057
X0499456Y0128666
X0518725Y0170525
X0459000Y0200500
X0487464Y0198566
X0457482Y0183523
X0502183Y0156709
X0453340Y0185670
X0499225Y0205296
X0592392Y0100623
X0593850Y0103755
X0595318Y0098854
X0598123Y0102023
X0604543Y0094886
X0601374Y0094048
X0603158Y0091535
X0589308Y0103990
X0588943Y0098963
X0626180Y0099276
X0623610Y0097125
X0626320Y0096084
X0623820Y0093654
X0626180Y0091919
X0623725Y0090422
X0626380Y0088518
X0623750Y0087130
X0624020Y0083243
X0626380Y0085117
X0454763Y0183503
X0487740Y0161235
X0500963Y0162261
X0551454Y0097154
X0525570Y0124623
X0471500Y0138000
X0536955Y0100257
X0555938Y0097292
X0569559Y0103123
X0560938Y0097195
X0487839Y0194142
X0520068Y0207142
X0532320Y0209470
X0473951Y0157235
X0444828Y0122132
X0502132Y0146686
X0508904Y0124063
X0491046Y0207506
X0490760Y0154771
X0452115Y0195057
X0455913Y0178698
X0533797Y0180764
X0533483Y0177449
X0527898Y0147146
X0542248Y0106333
X0511997Y0207730
X0526875Y0161838
X0518248Y0137692
X0495300Y0201600
X0547248Y0106582
X0578938Y0103123
X0618623Y0108918
X0527349Y0152246
X0518477Y0141401
X0478088Y0125219
X0474381Y0125310
X0441518Y0122242
X0443448Y0124552
X0458818Y0125422
X0458818Y0122065
X0452158Y0124582
X0450798Y0122254
X0453298Y0122254
X0452669Y0157140
X0455470Y0166963
X0455292Y0162797
X0539510Y0108742
X0566090Y0109136
X0484350Y0112811
X0487857Y0152147
X0467473Y0159766
X0487140Y0123397
X0491875Y0125222
X0494910Y0133316
X0474813Y0162220
X0546000Y0192000
X0544500Y0197500
X0542700Y0112881
X0550490Y0112989
X0494355Y0108674
X0550599Y0132596
X0552173Y0138528
X0551464Y0143862
X0526835Y0108314
X0519625Y0108543
X0512878Y0108635
X0536232Y0192086
X0500310Y0109211
X0581915Y0179955
X0562195Y0159015
X0558348Y0142511
X0558059Y0154254
X0539500Y0196500
X0550550Y0151682
X0504955Y0099830
X0500955Y0100139
X0508955Y0099978
X0496955Y0099958
X0520955Y0100444
X0516955Y0100333
X0524955Y0099359
X0512955Y0100428
X0461516Y0078275
X0458598Y0077967
X0532955Y0100604
X0528955Y0099781
X0628738Y0133012
X0550370Y0157461
X0564076Y0145372
X0538655Y0151415
X0532955Y0108669
X0546306Y0110193
X0462912Y0105704
X0457912Y0105704
X0460412Y0105704
X0439670Y0070044
X0442380Y0075513
X0546000Y0180000
X0544500Y0207000
X0587968Y0138765
X0592917Y0171906
X0593537Y0161023
X0555836Y0179259
X0557909Y0207537
X0549909Y0207060
X0542002Y0180100
X0572782Y0195199
X0569682Y0195199
X0447715Y0097926
X0446920Y0078358
X0453940Y0098586
X0453168Y0105144
X0449538Y0105144
X0502900Y0057670
X0487030Y0068075
X0461594Y0099342
X0513120Y0072069
X0458120Y0044721
X0594938Y0127893
X0592938Y0117657
X0628838Y0120216
X0617925Y0114064
X0600118Y0112568
X0605070Y0123991
X0592938Y0133232
X0492955Y0099440
X0595345Y0120216
X0583547Y0128232
X0583829Y0132232
X0580501Y0138336
X0579540Y0143304
X0580180Y0148894
X0583970Y0144589
X0563230Y0150222
X0538294Y0159415
X0593277Y0179955
X0535960Y0112850
X0479450Y0063721
X0464170Y0056436
X0475030Y0063879
X0475310Y0059746
X0483240Y0060546
X0486810Y0060785
X0582792Y0167632
X0541657Y0207645
X0551395Y0174172
X0555510Y0173872
X0557668Y0176534
X0559646Y0174476
X0563129Y0178369
X0581565Y0154969
X0561909Y0207393
X0450917Y0097566
X0484068Y0099980
X0488438Y0100123
X0464767Y0078145
X0553909Y0207401
X0558768Y0191223
X0547543Y0143415
X0548007Y0139415
X0592491Y0175906
X0594920Y0123370
X0584438Y0160933
X0583661Y0121836
X0583829Y0117732
X0548367Y0135415
X0558845Y0158697
X0454263Y0077675
X0457583Y0066384
X0446088Y0087659
X0446088Y0085159
X0446088Y0090159
X0462294Y0090259
X0462294Y0085259
X0462294Y0087759
X0466647Y0091224
X0466682Y0102410
X0446268Y0069074
X0450618Y0069004
X0588692Y0192809
X0582920Y0194220
X0632485Y0202077
X0624950Y0189801
X0632483Y0192781
X0624358Y0176090
X0579897Y0161355
X0624800Y0179953
X0613432Y0153528
X0624800Y0184953
X0592938Y0140689
X0563274Y0162169
X0595438Y0138130
X0563410Y0165289
X0550604Y0168072
X0557995Y0110244
X0488438Y0109623
X0552050Y0229124
X0552120Y0232388
X0549358Y0230153
X0549488Y0233003
X0544990Y0231086
X0546690Y0233066
X0631702Y0307880
X0632376Y0305257
X0634212Y0281670
X0631672Y0301066
X0624383Y0292591
X0576105Y0231626
X0593459Y0240780
X0550090Y0247079
X0547929Y0258102
X0545116Y0266847
X0563506Y0232027
X0566248Y0230283
X0561258Y0230153
X0566774Y0275195
X0568410Y0226647
X0567980Y0222353
X0572020Y0222393
X0572690Y0226569
X0560865Y0285434
X0555750Y0212029
X0545424Y0226722
X0535772Y0250076
X0617778Y0238873
X0612974Y0269095
X0622470Y0261628
X0575908Y0295606
X0575880Y0293016
X0592858Y0247079
X0593874Y0262395
X0581474Y0274795
X0594174Y0256695
X0564274Y0279395
X0585579Y0230095
X0595374Y0236795
X0545981Y0236287
X0594067Y0265168
X0565953Y0301635
X0591707Y0230162
X0561525Y0298192
X0566876Y0289890
X0610415Y0237441
X0557222Y0285109
X0593607Y0305034
X0545703Y0245725
X0596574Y0276393
X0588607Y0305034
X0594374Y0271395
X0557207Y0280328
X0555072Y0289563
X0590874Y0275195
X0539267Y0267102
X0579707Y0229395
X0545223Y0276895
X0538525Y0213425
X0569874Y0231795
X0551341Y0274262
X0557207Y0274828
X0550040Y0243929
X0536476Y0238993
X0536972Y0242993
X0591707Y0221095
X0587707Y0220728
X0583707Y0220762
X0585580Y0210516
X0544700Y0216100
X0558416Y0210682
X0547148Y0220220
X0547927Y0212190
X0539438Y0250323
X0536576Y0246993
X0536676Y0234993
X0604774Y0271893
X0604926Y0278476
X0605674Y0236295
X0595707Y0220995
X0585584Y0308881
X0575874Y0282395
X0578076Y0246693
X0579707Y0220662
X0608274Y0268795
X0608774Y0239995
X0608274Y0249795
X0592201Y0308988
X0624101Y0296525
X0578076Y0260093
X0578076Y0253393
X0575874Y0285995
X0575874Y0289895
X0592874Y0250995
X0604674Y0239995
X0600874Y0249795
X0596774Y0249795
X0604774Y0249795
X0600874Y0239795
X0597074Y0239995
X0604574Y0268795
X0600674Y0268795
X0596574Y0268695
X0564676Y0246693
X0571576Y0246693
X0564676Y0253693
X0564676Y0260093
X0571476Y0260093
X0633773Y0310439
X0633652Y0315198
X0632122Y0312898
X0622890Y0325227
X0616490Y0327534
X0619190Y0336986
X0627000Y0327926
X0625190Y0336986
X0630190Y0336986
X0631860Y0321455
X0628140Y0317610
X0633470Y0326710
X0623820Y0321062
X0609150Y0328514
X0536170Y0336603
X0536180Y0341432
X0547340Y0339103
X0543110Y0333848
X0541380Y0340358
X0553690Y0340829
X0579788Y0354743
X0601450Y0326509
X0600770Y0358702
X0597440Y0391690
X0612641Y0402478
X0612641Y0397478
X0607671Y0344818
X0609078Y0388557
X0618581Y0354818
X0628141Y0344818
X0607855Y0352341
X0609078Y0393557
X0611848Y0359784
X0630691Y0405007
X0548470Y0378127
X0552090Y0388953
X0581650Y0311446
X0576650Y0311446
X0594860Y0395088
X0598551Y0329541
X0590984Y0323246
X0585984Y0323246
X0624889Y0357778
X0620238Y0364369
X0617592Y0362539
X0608306Y0359971
X0604338Y0338285
X0627022Y0383713
X0553230Y0407251
X0549760Y0407251
X0619014Y0408353
X0555707Y0389146
X0583737Y0321204
X0579168Y0313641
X0608821Y0403445
X0613640Y0336986
X0591977Y0319360
X0583853Y0313783
X0605746Y0387837
X0605573Y0393920
X0608869Y0396959
X0633633Y0403717
X0616258Y0422211
X0611130Y0417928
X0630570Y0451450
X0546250Y0490302
X0632680Y0466669
X0605800Y0463167
X0603819Y0485332
X0628250Y0471142
X0591100Y0450128
X0578830Y0448192
X0543280Y0491040
X0589070Y0423525
X0609370Y0452974
X0588153Y0459599
X0630691Y0410007
X0564370Y0509117
X0617980Y0460408
X0610010Y0456581
X0610580Y0448662
X0564370Y0504117
X0625900Y0461769
X0631280Y0446007
X0622100Y0465822
X0626250Y0450248
X0547488Y0452373
X0546038Y0457523
X0546384Y0445107
X0535352Y0440414
X0600680Y0412780
X0598670Y0508170
X0547638Y0462356
X0572440Y0469323
X0572440Y0464323
X0538038Y0488323
X0555140Y0445940
X0544500Y0422583
X0541838Y0450723
X0534738Y0445523
X0543338Y0459323
X0536440Y0421973
X0541650Y0422280
X0540700Y0418852
X0549574Y0432582
X0557017Y0438968
X0565977Y0456156
X0566059Y0460956
X0545513Y0469740
X0554550Y0469674
X0562340Y0484252
X0622600Y0488753
X0540141Y0442994
X0565310Y0412700
X0630420Y0491511
X0590720Y0456076
X0553750Y0410420
X0621399Y0420400
X0633455Y0427209
X0611050Y0423087
X0567320Y0415088
X0551140Y0445789
X0622199Y0506535
X0605798Y0501238
X0575650Y0469996
X0571830Y0509411
X0579600Y0508878
X0548000Y0509493
X0547340Y0484025
X0556971Y0460656
X0556959Y0443009
X0535729Y0476632
X0540938Y0473623
X0536440Y0431923
X0541440Y0431787
X0575550Y0463784
X0539419Y0491107
X0542738Y0455823
X0542738Y0463123
X0556771Y0456156
X0561610Y0503885
X0633663Y0411009
X0543381Y0448428
X0535048Y0602885
X0541538Y0529625
X0551338Y0544225
X0551538Y0540325
X0551438Y0563825
X0543850Y0590313
X0535776Y0590487
X0551238Y0584025
X0561568Y0589355
X0542848Y0602975
X0550149Y0604639
X0568163Y0595115
X0561608Y0571775
X0566378Y0567725
X0563188Y0541925
X0561174Y0564471
X0577778Y0556355
X0538828Y0602945
X0568930Y0607754
X0561198Y0581793
X0565398Y0584765
X0540540Y0601008
X0574071Y0606204
X0565858Y0576195
X0586810Y0603344
X0566338Y0554235
X0566298Y0548465
X0575838Y0548935
X0549920Y0527242
X0562308Y0536895
X0554860Y0531701
X0576208Y0542405
X0616320Y0537066
X0596560Y0536108
X0622798Y0546764
X0603010Y0527908
X0575138Y0559825
X0575038Y0554725
X0544370Y0515267
X0544370Y0510267
X0593867Y0595695
X0573840Y0512108
X0593867Y0600695
X0578840Y0512108
X0625130Y0534199
X0613470Y0537495
X0583890Y0537093
X0602314Y0602641
X0602314Y0607641
X0567493Y0532225
X0545138Y0539725
X0551161Y0547148
X0551338Y0551100
X0583538Y0552225
X0584413Y0563198
X0588540Y0557418
X0596050Y0557563
X0604437Y0557956
X0609060Y0552101
X0621840Y0555040
X0621937Y0558276
X0551238Y0571725
X0582023Y0571242
X0578110Y0582149
X0540701Y0590162
X0547000Y0590163
X0578399Y0585696
X0596401Y0589852
X0612270Y0586543
X0632157Y0511230
X0604820Y0555040
X0605290Y0594166
X0606300Y0551844
X0610070Y0557588
X0612493Y0607666
X0617270Y0580443
X0609026Y0579132
X0605286Y0584152
X0611520Y0596594
X0627047Y0581066
X0621937Y0567143
X0605396Y0590552
X0610821Y0566494
X0627084Y0578257
X0624870Y0573143
X0601043Y0567781
X0592437Y0566543
X0586369Y0585801
X0553619Y0601204
X0634190Y0538267
X0613541Y0546764
X0609300Y0531638
X0621760Y0526967
X0596751Y0532108
X0624368Y0599741
X0624468Y0593241
X0630768Y0593241
X0624368Y0605941
X0632362Y0565543
X0605362Y0609413
X0607077Y0566915
X0609168Y0554851
X0591023Y0600384
X0590842Y0608112
X0590898Y0597158
X0596209Y0586903
X0596484Y0582903
X0596495Y0578903
X0596530Y0574903
X0589036Y0548825
X0547880Y0515743
X0560960Y0510151
X0574876Y0575625
X0574645Y0583525
X0575538Y0571725
X0575038Y0567725
X0574738Y0579525
X0574738Y0587425
X0575238Y0552025
X0575438Y0545425
X0544638Y0600525
X0548138Y0600425
X0536438Y0600425
X0550938Y0587325
X0551538Y0568525
X0545413Y0547950
X0560838Y0540325
X0568068Y0525306
X0544138Y0530125
X0541238Y0539625
X0534638Y0539825
X0561065Y0543998
X0551438Y0561225
X0585013Y0547959
X0574537Y0591325
X0567791Y0528325
X0605521Y0601097
X0539830Y0667332
X0615700Y0657757
X0615940Y0666862
X0620480Y0693827
X0620160Y0670594
X0612811Y0688422
X0612670Y0681438
X0552350Y0614028
X0617930Y0703520
X0536557Y0655498
X0545062Y0708679
X0596470Y0655231
X0540062Y0708779
X0592960Y0703291
X0585400Y0697289
X0607380Y0699671
X0565062Y0708679
X0589500Y0690546
X0565556Y0632431
X0543400Y0625963
X0591840Y0659568
X0596998Y0658008
X0597300Y0663128
X0543400Y0635615
X0555062Y0708679
X0550004Y0709559
X0591279Y0656223
X0560062Y0708679
X0595950Y0708997
X0580740Y0653286
X0576520Y0667750
X0576987Y0660180
X0579076Y0669603
X0542424Y0654821
X0551230Y0652844
X0551283Y0670800
X0551030Y0637200
X0558281Y0637840
X0539734Y0675020
X0563840Y0653515
X0565168Y0669614
X0576519Y0687665
X0577010Y0682718
X0576846Y0675985
X0578030Y0690236
X0576644Y0679562
X0565168Y0674614
X0549314Y0647594
X0580637Y0663629
X0563850Y0659575
X0600650Y0707835
X0577217Y0652002
X0565647Y0637705
X0600980Y0641533
X0566950Y0659439
X0559440Y0650767
X0600727Y0686876
X0565168Y0689614
X0563393Y0686908
X0565168Y0679614
X0565168Y0699614
X0563441Y0676872
X0604220Y0703774
X0563577Y0692284
X0602020Y0679156
X0563586Y0682137
X0600727Y0681876
X0600690Y0691896
X0576442Y0705492
X0565168Y0694614
X0574730Y0625521
X0571650Y0625998
X0555308Y0673156
X0555308Y0677156
X0555235Y0681156
X0555284Y0685156
X0555357Y0689156
X0610810Y0683933
X0610550Y0686640
X0610570Y0691156
X0555271Y0693156
X0555150Y0697156
X0584101Y0707893
X0588151Y0707857
X0579151Y0707857
X0610570Y0695156
X0588780Y0611056
X0588780Y0616056
X0565168Y0664614
X0600719Y0675156
X0631930Y0655254
X0615690Y0625536
X0541980Y0620227
X0566053Y0627509
X0585500Y0620926
X0541440Y0647594
X0579020Y0658250
X0555356Y0669156
X0555356Y0665156
X0539120Y0670129
X0630984Y0624829
X0616471Y0636215
X0630137Y0639312
X0634137Y0639352
X0607620Y0647169
X0593142Y0663828
X0579980Y0683140
X0589050Y0680160
X0610693Y0679333
X0618020Y0700000
X0610540Y0697964
X0539471Y0632476
X0583930Y0652439
X0577000Y0620029
X0551283Y0699243
X0600736Y0668425
X0612914Y0707630
X0602332Y0671156
X0608975Y0708094
X0620510Y0639427
X0535062Y0708679
X0623290Y0641222
X0622290Y0708516
X0571790Y0646799
X0612370Y0614143
X0627146Y0638932
X0588950Y0650070
X0611254Y0617943
X0627986Y0625895
X0629781Y0628559
X0623940Y0628720
X0611572Y0629894
X0613200Y0661577
X0634137Y0631342
X0608310Y0641603
X0622510Y0635544
X0612950Y0656140
X0613796Y0648705
X0605010Y0641435
X0616730Y0633290
X0614579Y0645072
X0579500Y0625963
X0538400Y0613804
X0546938Y0613828
X0542438Y0613723
X0629868Y0612241
X0624468Y0612141
X0590646Y0618751
X0607020Y0704644
X0614909Y0671938
X0634251Y0683493
X0617235Y0689036
X0621410Y0696941
X0617093Y0709167
X0540048Y0629641
X0552849Y0631652
X0535230Y0648711
X0545377Y0647594
X0576700Y0655594
X0587440Y0656958
X0594733Y0653385
X0584903Y0663828
X0610651Y0675156
X0587040Y0688218
X0586060Y0682582
X0544984Y0699419
X0547346Y0697581
X0568215Y0702343
X0586995Y0694080
X0565168Y0684614
X0601588Y0664798
X0629912Y0769200
X0632000Y0775400
X0632030Y0779137
X0570614Y0713237
X0609840Y0713617
X0620830Y0717516
X0553725Y0717251
X0557488Y0713709
X0562540Y0713454
X0594170Y0719290
X0555551Y0722342
X0580510Y0724421
X0557978Y0734053
X0598880Y0719232
X0564319Y0721587
X0577570Y0734118
X0583440Y0724927
X0566798Y0734023
X0574190Y0717805
X0585693Y0722428
X0571232Y0732545
X0569604Y0721248
X0537503Y0710088
X0579220Y0720776
X0557426Y0724436
X0539577Y0721891
X0549049Y0724412
X0544082Y0724460
X0560544Y0718091
X0601813Y0715579
X0550535Y0721903
X0584312Y0710716
X0606146Y0713145
X0628160Y0722343
X0544934Y0720820
X0601856Y0711479
X0603938Y0753623
X0546566Y0724119
X0543193Y0710787
X0547542Y0711523
X0592480Y0771514
X0597530Y0780191
X0579240Y0775147
X0587170Y0773768
X0572720Y0777184
X0554870Y0779438
X0550940Y0771858
X0545300Y0783152
X0539650Y0780942
X0609347Y0778624
X0606270Y0774615
X0612260Y0783106
X0569680Y0771106
X0562700Y0772391
X0560150Y0781347
X0624010Y0746351
X0620670Y0722216
X0613730Y0717663
X0616070Y0720838
X0632300Y0749755
X0625010Y0778281
X0619030Y0778682
X0631690Y0733744
X0619080Y0772610
X0630040Y0745114
X0609070Y0721917
X0553193Y0724847
X0535272Y0711217
X0633970Y0723033
X0633920Y0791476
X0629983Y0791476
X0610298Y0791476
X0614235Y0791476
X0618172Y0791476
X0594550Y0791476
X0598487Y0791476
X0574864Y0791476
X0578802Y0791476
X0555179Y0791476
X0559116Y0791476
X0535494Y0791476
X0539431Y0791476
X0596860Y0723422
X0628380Y0735476
X0623960Y0735141
X0621254Y0713788
X0611244Y0709830
X0535485Y0715182
X0562395Y0724557
X0568288Y0715547
X0568940Y0724090
X0573440Y0724053
X0577940Y0724127
X0587963Y0724108
X0623940Y0723503
X0541940Y0735681
X0537702Y0735662
X0546440Y0735681
X0550940Y0735681
X0555148Y0735583
X0560350Y0735807
X0564438Y0735853
X0573440Y0735681
X0568908Y0735883
X0587940Y0735681
X0593004Y0735662
X0583440Y0735856
X0596940Y0735681
X0608791Y0735775
X0605938Y0735665
X0601440Y0735681
X0614732Y0735517
X0619590Y0735383
X0592440Y0723768
X0646500Y0746300
X0652212Y0786700
X0636390Y0775395
X0657010Y0786039
X0646680Y0755009
X0689700Y0774500
X0647410Y0767053
X0646370Y0759252
X0649640Y0757527
X0638470Y0762212
X0640010Y0778215
X0639920Y0753526
X0721245Y0765576
X0651690Y0778099
X0650400Y0770522
X0716245Y0765576
X0672500Y0779579
X0669810Y0786721
X0681164Y0783461
X0681480Y0777388
X0731925Y0778490
X0729500Y0746300
X0704000Y0770800
X0726925Y0778490
X0731200Y0716200
X0730800Y0728400
X0699600Y0776000
X0669320Y0783845
X0677227Y0786454
X0673290Y0782855
X0664460Y0785890
X0677490Y0782114
X0676390Y0778439
X0656000Y0732400
X0659200Y0721454
X0658860Y0727383
X0644950Y0719110
X0656650Y0713057
X0636170Y0729335
X0654050Y0718086
X0672500Y0749179
X0672710Y0746235
X0675100Y0749300
X0638890Y0734879
X0657570Y0730414
X0683520Y0792080
X0683520Y0789080
X0684500Y0786665
X0657320Y0723584
X0655574Y0728674
X0709500Y0736800
X0657500Y0761500
X0652660Y0749000
X0635460Y0735130
X0636910Y0745815
X0729500Y0737400
X0706575Y0740425
X0722590Y0787885
X0721790Y0791408
X0709040Y0787507
X0708723Y0791092
X0704786Y0791274
X0665416Y0791476
X0661479Y0791476
X0730990Y0775334
X0727570Y0775278
X0721100Y0762903
X0718150Y0763015
X0656660Y0736218
X0639928Y0738905
X0653500Y0732583
X0654514Y0720674
X0648077Y0713569
X0688510Y0735294
X0672630Y0720752
X0705870Y0721832
X0654000Y0736400
X0659300Y0734119
X0642999Y0685781
X0656505Y0701191
X0640330Y0684439
X0703386Y0669774
X0732540Y0653829
X0659978Y0666274
X0727830Y0641829
X0733210Y0645829
X0728690Y0649829
X0657340Y0690286
X0708386Y0669774
X0693386Y0667241
X0698386Y0667241
X0673386Y0668420
X0713445Y0677641
X0678386Y0668420
X0718445Y0677641
X0721100Y0689400
X0655610Y0706309
X0639940Y0687841
X0665050Y0680648
X0670940Y0612070
X0648701Y0624774
X0642737Y0639413
X0646737Y0639413
X0657550Y0655072
X0651226Y0666288
X0646580Y0654775
X0656070Y0612743
X0655873Y0615540
X0685640Y0634154
X0687660Y0631799
X0683720Y0631732
X0717372Y0634474
X0713742Y0634373
X0719092Y0631682
X0716064Y0631749
X0712732Y0631749
X0642795Y0624818
X0658980Y0610043
X0649173Y0629876
X0641263Y0631393
X0636890Y0627095
X0646940Y0643448
X0654221Y0631425
X0647870Y0649784
X0644636Y0627257
X0659600Y0623785
X0663560Y0625019
X0718510Y0681526
X0713910Y0681330
X0707660Y0673204
X0703570Y0673036
X0698830Y0670652
X0692720Y0670540
X0671400Y0666151
X0681310Y0666671
X0656971Y0660492
X0667610Y0617197
X0655170Y0639432
X0650928Y0639290
X0654645Y0627064
X0664870Y0614543
X0638470Y0639290
X0635968Y0612241
X0643568Y0612341
X0688340Y0621294
X0685410Y0621250
X0711612Y0620383
X0720052Y0620480
X0715282Y0620282
X0663040Y0688057
X0656254Y0683277
X0668000Y0676595
X0689100Y0680291
X0708450Y0695489
X0669390Y0695406
X0646460Y0512967
X0675044Y0524581
X0677160Y0529422
X0708258Y0549815
X0687183Y0539585
X0678217Y0536752
X0686661Y0519199
X0698438Y0524890
X0707736Y0510140
X0712820Y0519647
X0684620Y0535923
X0690040Y0535797
X0694150Y0536155
X0641842Y0516730
X0719332Y0515757
X0668573Y0514155
X0664024Y0513414
X0659933Y0513927
X0634530Y0521565
X0645040Y0524444
X0640470Y0523266
X0645150Y0535704
X0700719Y0516954
X0696494Y0513677
X0673590Y0567696
X0677730Y0567706
X0673700Y0562515
X0677850Y0562515
X0673950Y0557314
X0678360Y0557426
X0712740Y0593101
X0686770Y0543325
X0667050Y0535324
X0646870Y0576243
X0646870Y0569443
X0652690Y0531693
X0716260Y0525295
X0716021Y0516945
X0706361Y0532632
X0719761Y0532432
X0723370Y0558906
X0720445Y0558990
X0726154Y0559002
X0731251Y0558975
X0728661Y0558934
X0654240Y0511568
X0701170Y0538508
X0668627Y0527718
X0668823Y0532470
X0641870Y0580743
X0646732Y0580781
X0655445Y0591918
X0655688Y0601761
X0655978Y0609635
X0634921Y0580163
X0651437Y0578943
X0639673Y0576888
X0636890Y0571351
X0713190Y0583032
X0713300Y0578995
X0691532Y0563789
X0691532Y0559789
X0691532Y0579789
X0691532Y0575789
X0691532Y0571789
X0691532Y0567789
X0695600Y0590788
X0691532Y0587789
X0691532Y0583789
X0710873Y0563230
X0710585Y0539103
X0701023Y0553658
X0678315Y0540752
X0659740Y0536019
X0664603Y0601976
X0661396Y0588900
X0665170Y0595943
X0651437Y0569676
X0643568Y0593241
X0643568Y0599541
X0636868Y0593141
X0643568Y0606641
X0643012Y0565243
X0638286Y0557415
X0638166Y0560972
X0729942Y0515757
X0691161Y0518684
X0712281Y0525785
X0727940Y0469943
X0726830Y0460815
X0636010Y0469995
X0726430Y0465371
X0731570Y0464043
X0706734Y0479786
X0683112Y0487660
X0694823Y0498932
X0698683Y0487517
X0707920Y0505575
X0687049Y0471912
X0690986Y0467975
X0690986Y0483723
X0687049Y0479786
X0702797Y0467975
X0702797Y0479786
X0702797Y0471912
X0651395Y0487265
X0692955Y0502112
X0689017Y0497282
X0684876Y0497385
X0713978Y0498075
X0683112Y0479786
X0659828Y0465162
X0702797Y0464038
X0636586Y0410910
X0650822Y0425295
X0655812Y0424106
X0673368Y0416621
X0671056Y0426300
X0720150Y0491632
X0732817Y0489435
X0702585Y0483749
X0729640Y0486848
X0725730Y0486788
X0683112Y0464038
X0696891Y0507279
X0700829Y0504041
X0648956Y0469323
X0719370Y0472436
X0651080Y0455238
X0683113Y0471941
X0674353Y0463842
X0689729Y0509580
X0710671Y0471913
X0664450Y0435739
X0662780Y0477039
X0653800Y0505331
X0704550Y0444407
X0706734Y0475850
X0646600Y0463571
X0710671Y0479786
X0691070Y0464058
X0677070Y0444820
X0721290Y0484381
X0682764Y0444832
X0702730Y0455483
X0635120Y0456136
X0706734Y0483723
X0718431Y0483368
X0672190Y0457216
X0715528Y0459332
X0653360Y0446280
X0720140Y0478333
X0648920Y0457851
X0673740Y0449887
X0658680Y0446610
X0715328Y0481122
X0647280Y0446851
X0683112Y0483723
X0731340Y0476723
X0650150Y0494337
X0692520Y0506898
X0680790Y0504521
X0726580Y0455637
X0662630Y0500823
X0636170Y0493028
X0667070Y0483608
X0710768Y0475972
X0660518Y0492862
X0647921Y0475778
X0650790Y0497730
X0678450Y0508438
X0661158Y0486152
X0650521Y0482930
X0704766Y0498880
X0667774Y0477992
X0641690Y0443656
X0635840Y0449890
X0638350Y0507893
X0679299Y0491473
X0672660Y0441007
X0706734Y0471913
X0651840Y0460012
X0660458Y0470932
X0648493Y0417221
X0663674Y0417999
X0634578Y0424964
X0727602Y0500100
X0652110Y0465238
X0687049Y0487660
X0674156Y0503662
X0690986Y0487660
X0668779Y0417135
X0653649Y0417582
X0658295Y0417662
X0653070Y0427500
X0679175Y0464038
X0687130Y0464132
X0643208Y0427819
X0658339Y0425601
X0648208Y0427819
X0663339Y0425601
X0689527Y0412843
X0666312Y0417742
X0651138Y0417385
X0665766Y0427868
X0650079Y0430289
X0656021Y0427864
X0641480Y0430289
X0646906Y0505210
X0646105Y0492010
X0635545Y0465888
X0634945Y0461888
X0731566Y0442136
X0712239Y0452293
X0698860Y0483723
X0698860Y0479786
X0687049Y0483723
X0690986Y0479786
X0698860Y0467975
X0690986Y0471912
X0687049Y0467975
X0698860Y0471912
X0714639Y0454872
X0707942Y0448676
X0666928Y0468132
X0667428Y0463432
X0664528Y0463432
X0680228Y0451432
X0683128Y0451332
X0672628Y0468032
X0669728Y0468032
X0670428Y0463532
X0646381Y0478679
X0686731Y0413349
X0636962Y0310928
X0635652Y0313118
X0648450Y0338711
X0656730Y0338633
X0679430Y0350013
X0634511Y0389156
X0691037Y0401739
X0685859Y0403970
X0652139Y0377125
X0701770Y0331938
X0669215Y0377488
X0636938Y0402885
X0688118Y0381043
X0679590Y0352829
X0687869Y0386780
X0648425Y0373474
X0677083Y0375124
X0640647Y0339854
X0646171Y0364676
X0645236Y0377858
X0641236Y0381616
X0663632Y0366698
X0639838Y0349818
X0668925Y0364887
X0655122Y0315070
X0678838Y0407785
X0678986Y0392661
X0642863Y0358010
X0648838Y0349785
X0653938Y0364885
X0662390Y0377039
X0636990Y0386464
X0637614Y0397259
X0659543Y0377086
X0677946Y0387211
X0680017Y0403143
X0679138Y0397985
X0637738Y0392034
X0689527Y0407843
X0686686Y0392522
X0686686Y0397522
X0646013Y0358110
X0689864Y0398141
X0689864Y0392130
X0678338Y0405185
X0674235Y0379364
X0678099Y0389915
X0679552Y0372873
X0661140Y0386283
X0660138Y0365885
X0660899Y0311515
X0644105Y0311965
X0640171Y0311965
X0650162Y0318398
X0653162Y0318398
X0654352Y0323938
X0651352Y0323938
X0654340Y0386283
X0661940Y0408383
X0654840Y0408483
X0672752Y0366160
X0669540Y0386283
X0669540Y0402783
X0669440Y0408483
X0669440Y0395183
X0647440Y0386383
X0647340Y0400083
X0647440Y0408383
X0647340Y0393283
X0687121Y0407004
X0666270Y0359134
X0635000Y0265400
X0649995Y0296433
X0640112Y0285042
X0639350Y0250123
X0642932Y0284768
X0659350Y0298810
X0654060Y0302459
X0652362Y0306598
X0654962Y0307698
X0656270Y0299379
X0657838Y0238407
X0655030Y0223744
X0657838Y0243407
X0655030Y0228744
X0687584Y0251770
X0661190Y0246085
X0658601Y0229770
X0658582Y0222614
X0700994Y0221368
X0700947Y0216868
X0701687Y0212132
X0653352Y0291388
X0644113Y0297071
X0641227Y0297070
X0671166Y0302550
X0671129Y0305579
X0643170Y0294282
X0640448Y0294422
X0665390Y0214916
X0660770Y0214951
X0661160Y0235485
X0669320Y0214986
X0681870Y0214942
X0678750Y0214908
X0680310Y0217357
X0691690Y0212100
X0691970Y0216820
X0687584Y0233034
X0692010Y0221158
X0639200Y0170100
X0751080Y0100293
X0747710Y0100293
X0744790Y0106938
X0744760Y0103711
X0689480Y0194615
X0689480Y0191144
X0697850Y0186441
X0693520Y0186376
X0682140Y0194615
X0682140Y0191214
X0680100Y0188182
X0676590Y0188198
X0634962Y0195121
X0634962Y0200121
X0726500Y0123466
X0726470Y0126659
X0726400Y0130303
X0698150Y0136791
X0700060Y0144981
X0699990Y0149631
X0687546Y0154228
X0655695Y0164567
X0655695Y0159567
X0655642Y0149915
X0655642Y0144915
X0638970Y0132241
X0687571Y0172292
X0691314Y0145071
X0691280Y0149571
X0691148Y0140140
X0667300Y0188112
X0658972Y0158337
X0658959Y0165625
X0658767Y0151013
X0658769Y0143630
X0762630Y0103302
X0726160Y0112508
X0738650Y0105360
X0738620Y0109351
X0762590Y0106529
X0664560Y0191443
X0664560Y0195018
X0665320Y0203247
X0669250Y0203317
X0660700Y0203282
X0670280Y0188112
X0689500Y0120441
X0681770Y0203514
X0678650Y0203480
X0689820Y0203491
X0680220Y0200725
X0689820Y0200159
X0697800Y0205879
X0693540Y0205721
X0719800Y0024920
X0639957Y0053849
X0669987Y0053672
X0675927Y0053779
X0659947Y0053722
X0751180Y0110209
X0748070Y0110209
X0745070Y0110183
X0711676Y0051019
X0643957Y0053688
X0655947Y0053677
X0738370Y0123395
X0747080Y0129815
X0738340Y0126588
X0738270Y0130232
X0754580Y0124020
X0750930Y0129815
X0754610Y0127247
X0726190Y0105325
X0708130Y0106389
X0726160Y0109316
X0738620Y0112543
X0688160Y0064459
X0679927Y0053881
X0707176Y0050574
X0670980Y0077061
X0706380Y0075482
X0671810Y0106472
X0765610Y0361194
X0753230Y0328262
X0745220Y0327250
X0747600Y0323527
X0755500Y0337791
X0754850Y0335055
X0759400Y0334839
X0750700Y0323771
X0750350Y0311343
X0750430Y0314330
X0765250Y0357789
X0745500Y0492500
X0734575Y0492575
X0743150Y0483502
X0743364Y0478975
X0737350Y0459823
X0737350Y0464330
X0758500Y0469500
X0738130Y0502748
X0748723Y0455332
X0736310Y0450774
X0758494Y0455532
X0748300Y0496800
X0757500Y0474000
X0741401Y0454832
X0757823Y0451032
X0758223Y0446532
X0742779Y0487639
X0747460Y0582318
X0747470Y0585542
X0751730Y0583047
X0744050Y0571834
X0743951Y0578833
X0744090Y0575066
X0744020Y0566143
X0770850Y0587025
X0770710Y0584054
X0770850Y0575760
X0771110Y0578643
X0766950Y0558318
X0766900Y0572869
X0766920Y0564080
X0766840Y0561290
X0766900Y0567233
X0766820Y0569897
X0744000Y0647919
X0749520Y0658372
X0752960Y0653967
X0734460Y0791654
X0734460Y0788654
M00
X-0032872Y0130713
X-0035872Y0130713
X-0038872Y0130713
X-0032872Y0238033
X-0035872Y0238033
X-0038872Y0238033
X-0032872Y0238033
X-0035872Y0238033
X-0038872Y0238033
X-0038872Y0748993
X-0035872Y0748993
X-0032872Y0748993
M00
X0413386Y0390945
X0403543Y0387008
X0399606Y0377165
X0403543Y0367322
X0413386Y0363385
X0423229Y0367322
X0427166Y0377165
X0423229Y0387008
M00
X0611702Y0178997
X0611702Y0185690
X0611702Y0193997
X0611702Y0200690
X0605796Y0204845
X0605796Y0174845
X0605796Y0189845
M00
X0041930Y0214268
X0041930Y0220276
X0036024Y0211264
X0036024Y0217272
X0041930Y0178221
X0041930Y0184229
X0041930Y0190237
X0041930Y0196245
X0041930Y0202253
X0041930Y0208260
X0036024Y0181225
X0036024Y0187233
X0036024Y0193241
X0036024Y0199249
X0036024Y0205257
M00
X0615657Y0092789
X0615657Y0084915
X0615657Y0077041
X0615657Y0069167
X0590999Y0092789
X0590999Y0084915
X0590999Y0077041
X0590999Y0069167
M00
X0020859Y0109561
X0010859Y0109561
X0073740Y0020708
X0078740Y0030708
X0083740Y0020708
X0507489Y0360278
X0712975Y0252261
X0712975Y0244261
X0723275Y0252261
X0723275Y0244261
X0712975Y0262061
X0712975Y0234461
X0723275Y0262061
X0723275Y0234461
X0712975Y0173455
X0712975Y0165455
X0723275Y0173455
X0723275Y0165455
X0712975Y0183255
X0712975Y0155655
X0723275Y0183255
X0723275Y0155655
X0703661Y0020708
X0708661Y0030708
X0713661Y0020708
M00
X0556181Y0081889
X0546181Y0081889
M00
X0507489Y0281538
M00
X0617371Y0038803
X0617371Y0028803
X0607371Y0028803
X0607371Y0038803
X0597371Y0028803
X0587371Y0028803
X0597371Y0038803
X0587371Y0038803
X0577371Y0028803
X0577371Y0038803
X0554780Y0038803
X0554780Y0028803
X0544780Y0028803
X0544780Y0038803
X0534780Y0028803
X0534780Y0038803
X0524780Y0028803
X0524780Y0038803
X0514780Y0028803
X0514780Y0038803
X0679963Y0038803
X0679963Y0028803
X0669963Y0028803
X0669963Y0038803
X0659963Y0028803
X0649963Y0028803
X0659963Y0038803
X0649963Y0038803
X0639963Y0028803
X0639963Y0038803
M00
X0086880Y0143269
X0076880Y0143269
X0749968Y0029361
X0739968Y0029361
M00
X0605796Y0165160
X0609733Y0215672
M00
X0023628Y0338300
X0023628Y0321764
X0045282Y0338300
X0045282Y0321764
M00
X0711575Y0274161
X0711575Y0222361
X0733975Y0274161
X0733975Y0222361
X0711575Y0195355
X0711575Y0143555
X0733975Y0195355
X0733975Y0143555
M00
X0481102Y0034528
M00
X0393718Y0038554
X0354348Y0038554
M00
X0414961Y0098622
M00
X0434102Y0232640
X0434102Y0311875
X0608571Y0069167
X0583913Y0069167
M00
X-0044872Y0141213
X-0026872Y0141213
X-0044872Y0125213
X-0026872Y0125213
X-0026872Y0248533
X-0044872Y0248533
X-0026872Y0232533
X-0044872Y0232533
X-0044872Y0248533
X-0026872Y0248533
X-0044872Y0232533
X-0026872Y0232533
X-0026872Y0738493
X-0044872Y0738493
X-0026872Y0754493
X-0044872Y0754493
M00
X0043898Y0231457
X0043898Y0168544
M00
X0151969Y0098622
M00
X0102362Y0349606
X0102362Y0247244
X0354331Y0247244
X0354331Y0349606
M00
X0025439Y0303260
X0025439Y0356804
M00
X0098426Y0719685
X0098426Y0105512
M00
X0688977Y0719488
X0688977Y0105315
M00
X0413386Y0377165
M30
